FILE_TYPE = MACRO_DRAWING;
SET COLOR_WIRE YELLOW;
SET COLOR_PROP MONO;
SET COLOR_DOT WHITE;
SET COLOR_ARC YELLOW;
SET COLOR_BODY GREEN;
SET COLOR_NOTE MONO;
SET PROP_DISPLAY VALUE;
SET PAGE_NUMBER P90;
FORCEADD OFFPAGE..2
(475 3400);
FORCEPROP 2 LAST $XR0 21 
J 0
(664 3400);
DISPLAY 0.638298 (664 3400);
PAINT MONO (664 3400);
FORCEPROP 1 LAST COMMENT_BODY TRUE
J 0
(430 3305);
DISPLAY 1.170213 (430 3305);
PAINT GREEN (430 3305);
DISPLAY INVISIBLE (430 3305);
FORCEPROP 2 LAST CDS_LIB mstr_standard
J 0
(475 3400);
PAINT ORANGE (475 3400);
DISPLAY INVISIBLE (475 3400);
FORCEPROP 2 LAST PATH I1
J 0
(675 3450);
DISPLAY 1.021277 (675 3450);
PAINT ORANGE (675 3450);
DISPLAY INVISIBLE (675 3450);
FORCEPROP 1 LAST OFFPAGE TRUE
J 0
(800 3275);
PAINT GREEN (800 3275);
DISPLAY INVISIBLE (800 3275);
FORCEADD OFFPAGE..2
(550 1050);
FORCEPROP 2 LAST $XR0 55 
J 0
(739 1050);
DISPLAY 0.638298 (739 1050);
PAINT MONO (739 1050);
FORCEPROP 1 LAST COMMENT_BODY TRUE
J 0
(505 955);
DISPLAY 1.170213 (505 955);
PAINT GREEN (505 955);
DISPLAY INVISIBLE (505 955);
FORCEPROP 1 LAST OFFPAGE TRUE
J 0
(875 925);
PAINT GREEN (875 925);
DISPLAY INVISIBLE (875 925);
FORCEPROP 2 LAST CDS_LIB mstr_standard
J 0
(550 1050);
PAINT ORANGE (550 1050);
DISPLAY INVISIBLE (550 1050);
FORCEPROP 2 LAST PATH I10
J 0
(750 1100);
DISPLAY 1.021277 (750 1100);
PAINT ORANGE (750 1100);
DISPLAY INVISIBLE (750 1100);
FORCEADD RES..1
(-325 1275);
FORCEPROP 1 LAST LOCATION R3D12
J 0
(-600 1300);
DISPLAY 0.617021 (-600 1300);
PAINT AQUA (-600 1300);
FORCEPROP 1 LAST PART_NUMBER G21796-294
J 0
(-675 1225);
DISPLAY 0.617021 (-675 1225);
PAINT BLUE (-675 1225);
FORCEPROP 1 LASTPIN (-425 1275) $PN 1
J 0
(-413 1287);
DISPLAY 0.617021 (-413 1287);
PAINT MONO (-413 1287);
FORCEPROP 1 LAST VALUE 240
J 2
(-250 1325);
DISPLAY 0.617021 (-250 1325);
PAINT SKYBLUE (-250 1325);
FORCEPROP 1 LAST PACK_TYPE 0402
J 0
(-300 1225);
DISPLAY 0.617021 (-300 1225);
PAINT SKYBLUE (-300 1225);
FORCEPROP 1 LASTPIN (-225 1275) $PN 2
J 0
(-263 1287);
DISPLAY 0.617021 (-263 1287);
PAINT MONO (-263 1287);
FORCEPROP 1 LAST TOLERANCE 1.0%
J 0
(-225 1325);
DISPLAY 0.617021 (-225 1325);
PAINT SKYBLUE (-225 1325);
FORCEPROP 1 LAST MATERIAL CHIP
J 0
(-100 1225);
DISPLAY 0.617021 (-100 1225);
PAINT RED (-100 1225);
FORCEPROP 1 LAST WATTAGE 1/16W
J 2
(300 1225);
DISPLAY 0.617021 (300 1225);
PAINT SKYBLUE (300 1225);
FORCEPROP 2 LAST CDS_LOCATION R3D12
J 0
(-600 1300);
DISPLAY 0.617021 (-600 1300);
PAINT AQUA (-600 1300);
DISPLAY INVISIBLE (-600 1300);
FORCEPROP 2 LAST CDS_LIB mstr_discrete
J 0
(-325 1275);
PAINT ORANGE (-325 1275);
DISPLAY INVISIBLE (-325 1275);
FORCEPROP 2 LAST BOM_COST PROC
J 0
(-325 1275);
PAINT MONO (-325 1275);
DISPLAY INVISIBLE (-325 1275);
FORCEPROP 2 LAST SEC_TYPE 0402
J 0
(-375 1475);
PAINT MONO (-375 1475);
DISPLAY INVISIBLE (-375 1475);
FORCEPROP 2 LAST SEC 1
J 0
(-375 1475);
DISPLAY 0.936170 (-375 1475);
PAINT MONO (-375 1475);
DISPLAY INVISIBLE (-375 1475);
FORCEPROP 1 LAST PATH I11
J 0
(-375 1425);
DISPLAY 0.978723 (-375 1425);
PAINT WHITE (-375 1425);
DISPLAY INVISIBLE (-375 1425);
FORCEPROP 2 LAST ROOM PROC_SIDEBAND
J 0
(-225 1375);
PAINT MONO (-225 1375);
DISPLAY INVISIBLE (-225 1375);
FORCEADD RES..1
(-325 1050);
FORCEPROP 1 LAST PART_NUMBER G21796-294
J 0
(-675 1000);
DISPLAY 0.617021 (-675 1000);
PAINT BLUE (-675 1000);
FORCEPROP 1 LAST PACK_TYPE 0402
J 0
(-300 1000);
DISPLAY 0.617021 (-300 1000);
PAINT SKYBLUE (-300 1000);
FORCEPROP 1 LAST LOCATION R3D13
J 0
(-600 1075);
DISPLAY 0.617021 (-600 1075);
PAINT AQUA (-600 1075);
FORCEPROP 1 LASTPIN (-425 1050) $PN 1
J 0
(-413 1062);
DISPLAY 0.617021 (-413 1062);
PAINT MONO (-413 1062);
FORCEPROP 1 LAST VALUE 240
J 2
(-250 1100);
DISPLAY 0.617021 (-250 1100);
PAINT SKYBLUE (-250 1100);
FORCEPROP 1 LASTPIN (-225 1050) $PN 2
J 0
(-263 1062);
DISPLAY 0.617021 (-263 1062);
PAINT MONO (-263 1062);
FORCEPROP 1 LAST TOLERANCE 1.0%
J 0
(-225 1100);
DISPLAY 0.617021 (-225 1100);
PAINT SKYBLUE (-225 1100);
FORCEPROP 1 LAST WATTAGE 1/16W
J 2
(325 1000);
DISPLAY 0.617021 (325 1000);
PAINT SKYBLUE (325 1000);
FORCEPROP 1 LAST MATERIAL EMPTY
J 0
(-100 1000);
DISPLAY 0.617021 (-100 1000);
PAINT RED (-100 1000);
FORCEPROP 2 LAST CDS_LOCATION R3D13
J 0
(-600 1075);
DISPLAY 0.617021 (-600 1075);
PAINT AQUA (-600 1075);
DISPLAY INVISIBLE (-600 1075);
FORCEPROP 2 LAST CDS_LIB mstr_discrete
J 0
(-325 1050);
PAINT ORANGE (-325 1050);
DISPLAY INVISIBLE (-325 1050);
FORCEPROP 2 LAST BOM_COST PROC
J 2
(-325 1050);
PAINT MONO (-325 1050);
DISPLAY INVISIBLE (-325 1050);
FORCEPROP 1 LAST PATH I12
J 0
(-375 1200);
DISPLAY 0.978723 (-375 1200);
PAINT WHITE (-375 1200);
DISPLAY INVISIBLE (-375 1200);
FORCEPROP 2 LAST SEC_TYPE 0402
J 0
(-375 1250);
PAINT MONO (-375 1250);
DISPLAY INVISIBLE (-375 1250);
FORCEPROP 2 LAST SEC 1
J 0
(-375 1250);
DISPLAY 0.936170 (-375 1250);
PAINT MONO (-375 1250);
DISPLAY INVISIBLE (-375 1250);
FORCEPROP 2 LAST ROOM PROC_SIDEBAND
J 0
(-225 1150);
PAINT MONO (-225 1150);
DISPLAY INVISIBLE (-225 1150);
FORCEADD OFFPAGE..2
(-1300 3800);
FORCEPROP 2 LAST $XR0 21 
J 0
(-1111 3800);
DISPLAY 0.638298 (-1111 3800);
PAINT MONO (-1111 3800);
FORCEPROP 1 LAST COMMENT_BODY TRUE
J 0
(-1345 3705);
DISPLAY 1.170213 (-1345 3705);
PAINT GREEN (-1345 3705);
DISPLAY INVISIBLE (-1345 3705);
FORCEPROP 2 LAST CDS_LIB mstr_standard
J 0
(-1300 3800);
PAINT ORANGE (-1300 3800);
DISPLAY INVISIBLE (-1300 3800);
FORCEPROP 2 LAST PATH I14
J 0
(-1100 3850);
DISPLAY 1.021277 (-1100 3850);
PAINT ORANGE (-1100 3850);
DISPLAY INVISIBLE (-1100 3850);
FORCEPROP 1 LAST OFFPAGE TRUE
J 0
(-975 3675);
PAINT GREEN (-975 3675);
DISPLAY INVISIBLE (-975 3675);
FORCEADD OFFPAGE..2
(-1350 1875);
FORCEPROP 2 LAST $XR0 55 
J 0
(-1161 1875);
DISPLAY 0.638298 (-1161 1875);
PAINT MONO (-1161 1875);
FORCEPROP 1 LAST COMMENT_BODY TRUE
J 0
(-1395 1780);
DISPLAY 1.170213 (-1395 1780);
PAINT GREEN (-1395 1780);
DISPLAY INVISIBLE (-1395 1780);
FORCEPROP 2 LAST CDS_LIB mstr_standard
J 0
(-1350 1875);
PAINT ORANGE (-1350 1875);
DISPLAY INVISIBLE (-1350 1875);
FORCEPROP 1 LAST OFFPAGE TRUE
J 0
(-1025 1750);
PAINT GREEN (-1025 1750);
DISPLAY INVISIBLE (-1025 1750);
FORCEPROP 2 LAST PATH I16
J 0
(-1150 1925);
DISPLAY 1.021277 (-1150 1925);
PAINT ORANGE (-1150 1925);
DISPLAY INVISIBLE (-1150 1925);
FORCEADD RES..1
(-2450 1875);
FORCEPROP 1 LAST LOCATION R3D22
J 0
(-2725 1900);
DISPLAY 0.617021 (-2725 1900);
PAINT AQUA (-2725 1900);
FORCEPROP 1 LAST PART_NUMBER G21796-294
J 0
(-2800 1825);
DISPLAY 0.617021 (-2800 1825);
PAINT BLUE (-2800 1825);
FORCEPROP 1 LASTPIN (-2550 1875) $PN 1
J 0
(-2538 1887);
DISPLAY 0.617021 (-2538 1887);
PAINT MONO (-2538 1887);
FORCEPROP 1 LAST VALUE 240
J 2
(-2375 1925);
DISPLAY 0.617021 (-2375 1925);
PAINT SKYBLUE (-2375 1925);
FORCEPROP 1 LAST PACK_TYPE 0402
J 0
(-2425 1825);
DISPLAY 0.617021 (-2425 1825);
PAINT SKYBLUE (-2425 1825);
FORCEPROP 1 LASTPIN (-2350 1875) $PN 2
J 0
(-2388 1887);
DISPLAY 0.617021 (-2388 1887);
PAINT MONO (-2388 1887);
FORCEPROP 1 LAST TOLERANCE 1.0%
J 0
(-2350 1925);
DISPLAY 0.617021 (-2350 1925);
PAINT SKYBLUE (-2350 1925);
FORCEPROP 1 LAST MATERIAL EMPTY
J 0
(-2225 1825);
DISPLAY 0.617021 (-2225 1825);
PAINT RED (-2225 1825);
FORCEPROP 1 LAST WATTAGE 1/16W
J 2
(-2100 1925);
DISPLAY 0.617021 (-2100 1925);
PAINT SKYBLUE (-2100 1925);
FORCEPROP 2 LAST CDS_LOCATION R3D22
J 0
(-2725 1900);
DISPLAY 0.617021 (-2725 1900);
PAINT AQUA (-2725 1900);
DISPLAY INVISIBLE (-2725 1900);
FORCEPROP 2 LAST BOM_COST PROC
J 2
(-2450 1875);
PAINT MONO (-2450 1875);
DISPLAY INVISIBLE (-2450 1875);
FORCEPROP 2 LAST CDS_LIB mstr_discrete
J 0
(-2450 1875);
PAINT ORANGE (-2450 1875);
DISPLAY INVISIBLE (-2450 1875);
FORCEPROP 2 LAST ROOM PROC_SIDEBAND
J 0
(-2100 1975);
PAINT MONO (-2100 1975);
DISPLAY INVISIBLE (-2100 1975);
FORCEPROP 1 LAST PATH I17
J 0
(-2500 2025);
DISPLAY 0.978723 (-2500 2025);
PAINT WHITE (-2500 2025);
DISPLAY INVISIBLE (-2500 2025);
FORCEPROP 2 LAST SEC 1
J 0
(-2500 2075);
DISPLAY 0.936170 (-2500 2075);
PAINT MONO (-2500 2075);
DISPLAY INVISIBLE (-2500 2075);
FORCEPROP 2 LAST SEC_TYPE 0402
J 0
(-2500 2075);
PAINT MONO (-2500 2075);
DISPLAY INVISIBLE (-2500 2075);
FORCEADD GND..1
(-725 525);
FORCEPROP 3 LASTPIN (-725 575) SIG_NAME GND\g
J 0
(-715 585);
DISPLAY 0.659574 (-715 585);
PAINT MONO (-715 585);
DISPLAY INVISIBLE (-715 585);
FORCEPROP 1 LAST SIZE 1B
J 0
(-650 475);
DISPLAY 0.872340 (-650 475);
PAINT GREEN (-650 475);
DISPLAY INVISIBLE (-650 475);
FORCEPROP 1 LAST BODY_TYPE PLUMBING
J 0
(-770 482);
DISPLAY 0.340426 (-770 482);
PAINT GREEN (-770 482);
DISPLAY INVISIBLE (-770 482);
FORCEPROP 1 LAST PATH I18
J 0
(-650 525);
DISPLAY 0.872340 (-650 525);
PAINT AQUA (-650 525);
DISPLAY INVISIBLE (-650 525);
FORCEPROP 1 LAST VOLTAGE 0
J 0
(-725 525);
PAINT SKYBLUE (-725 525);
DISPLAY INVISIBLE (-725 525);
FORCEPROP 2 LAST CDS_LIB mstr_symbols
J 0
(-725 525);
PAINT ORANGE (-725 525);
DISPLAY INVISIBLE (-725 525);
FORCEPROP 1 LAST HDL_POWER GND
J 0
(-725 675);
DISPLAY 0.872340 (-725 675);
PAINT GREEN (-725 675);
DISPLAY INVISIBLE (-725 675);
FORCEADD OFFPAGE..2
(-1350 1675);
FORCEPROP 2 LAST $XR0 156 
J 0
(-1161 1675);
DISPLAY 0.638298 (-1161 1675);
PAINT MONO (-1161 1675);
FORCEPROP 2 LAST $XR1 55 
J 0
(-1041 1675);
DISPLAY 0.638298 (-1041 1675);
PAINT MONO (-1041 1675);
FORCEPROP 2 LAST CDS_LIB mstr_standard
J 0
(-1350 1675);
PAINT ORANGE (-1350 1675);
DISPLAY INVISIBLE (-1350 1675);
FORCEPROP 1 LAST COMMENT_BODY TRUE
J 0
(-1395 1580);
DISPLAY 1.170213 (-1395 1580);
PAINT GREEN (-1395 1580);
DISPLAY INVISIBLE (-1395 1580);
FORCEPROP 2 LAST PATH I19
J 0
(-1150 1725);
DISPLAY 1.021277 (-1150 1725);
PAINT ORANGE (-1150 1725);
DISPLAY INVISIBLE (-1150 1725);
FORCEPROP 1 LAST OFFPAGE TRUE
J 0
(-1025 1550);
PAINT GREEN (-1025 1550);
DISPLAY INVISIBLE (-1025 1550);
FORCEADD OFFPAGE..2
(475 3200);
FORCEPROP 2 LAST $XR0 21 
J 0
(664 3200);
DISPLAY 0.638298 (664 3200);
PAINT MONO (664 3200);
FORCEPROP 2 LAST CDS_LIB mstr_standard
J 0
(475 3200);
PAINT ORANGE (475 3200);
DISPLAY INVISIBLE (475 3200);
FORCEPROP 1 LAST COMMENT_BODY TRUE
J 0
(430 3105);
DISPLAY 1.170213 (430 3105);
PAINT GREEN (430 3105);
DISPLAY INVISIBLE (430 3105);
FORCEPROP 2 LAST PATH I2
J 0
(675 3250);
DISPLAY 1.021277 (675 3250);
PAINT ORANGE (675 3250);
DISPLAY INVISIBLE (675 3250);
FORCEPROP 1 LAST OFFPAGE TRUE
J 0
(800 3075);
PAINT GREEN (800 3075);
DISPLAY INVISIBLE (800 3075);
FORCEADD OFFPAGE..2
(-1350 1475);
FORCEPROP 2 LAST $XR0 55 
J 0
(-1161 1475);
DISPLAY 0.638298 (-1161 1475);
PAINT MONO (-1161 1475);
FORCEPROP 1 LAST COMMENT_BODY TRUE
J 0
(-1395 1380);
DISPLAY 1.170213 (-1395 1380);
PAINT GREEN (-1395 1380);
DISPLAY INVISIBLE (-1395 1380);
FORCEPROP 2 LAST CDS_LIB mstr_standard
J 0
(-1350 1475);
PAINT ORANGE (-1350 1475);
DISPLAY INVISIBLE (-1350 1475);
FORCEPROP 1 LAST OFFPAGE TRUE
J 0
(-1025 1350);
PAINT GREEN (-1025 1350);
DISPLAY INVISIBLE (-1025 1350);
FORCEPROP 2 LAST PATH I20
J 0
(-1150 1525);
DISPLAY 1.021277 (-1150 1525);
PAINT ORANGE (-1150 1525);
DISPLAY INVISIBLE (-1150 1525);
FORCEADD OFFPAGE..2
(-1350 1275);
FORCEPROP 2 LAST $XR0 55 
J 0
(-1161 1275);
DISPLAY 0.638298 (-1161 1275);
PAINT MONO (-1161 1275);
FORCEPROP 1 LAST COMMENT_BODY TRUE
J 0
(-1395 1180);
DISPLAY 1.170213 (-1395 1180);
PAINT GREEN (-1395 1180);
DISPLAY INVISIBLE (-1395 1180);
FORCEPROP 2 LAST CDS_LIB mstr_standard
J 0
(-1350 1275);
PAINT ORANGE (-1350 1275);
DISPLAY INVISIBLE (-1350 1275);
FORCEPROP 1 LAST OFFPAGE TRUE
J 0
(-1025 1150);
PAINT GREEN (-1025 1150);
DISPLAY INVISIBLE (-1025 1150);
FORCEPROP 2 LAST PATH I23
J 0
(-1150 1325);
DISPLAY 1.021277 (-1150 1325);
PAINT ORANGE (-1150 1325);
DISPLAY INVISIBLE (-1150 1325);
FORCEADD RES..1
(-2450 1675);
FORCEPROP 1 LAST LOCATION R3D16
J 0
(-2725 1700);
DISPLAY 0.617021 (-2725 1700);
PAINT AQUA (-2725 1700);
FORCEPROP 1 LAST PART_NUMBER G21796-294
J 0
(-2800 1625);
DISPLAY 0.617021 (-2800 1625);
PAINT BLUE (-2800 1625);
FORCEPROP 1 LASTPIN (-2550 1675) $PN 1
J 0
(-2538 1687);
DISPLAY 0.617021 (-2538 1687);
PAINT MONO (-2538 1687);
FORCEPROP 1 LAST VALUE 240
J 2
(-2375 1725);
DISPLAY 0.617021 (-2375 1725);
PAINT SKYBLUE (-2375 1725);
FORCEPROP 1 LAST PACK_TYPE 0402
J 0
(-2425 1625);
DISPLAY 0.617021 (-2425 1625);
PAINT SKYBLUE (-2425 1625);
FORCEPROP 1 LASTPIN (-2350 1675) $PN 2
J 0
(-2388 1687);
DISPLAY 0.617021 (-2388 1687);
PAINT MONO (-2388 1687);
FORCEPROP 1 LAST TOLERANCE 1.0%
J 0
(-2350 1725);
DISPLAY 0.617021 (-2350 1725);
PAINT SKYBLUE (-2350 1725);
FORCEPROP 1 LAST MATERIAL EMPTY
J 0
(-2225 1625);
DISPLAY 0.617021 (-2225 1625);
PAINT RED (-2225 1625);
FORCEPROP 1 LAST WATTAGE 1/16W
J 2
(-2100 1725);
DISPLAY 0.617021 (-2100 1725);
PAINT SKYBLUE (-2100 1725);
FORCEPROP 2 LAST CDS_LOCATION R3D16
J 0
(-2725 1700);
DISPLAY 0.617021 (-2725 1700);
PAINT AQUA (-2725 1700);
DISPLAY INVISIBLE (-2725 1700);
FORCEPROP 2 LAST BOM_COST PROC
J 0
(-2450 1675);
PAINT MONO (-2450 1675);
DISPLAY INVISIBLE (-2450 1675);
FORCEPROP 2 LAST CDS_LIB mstr_discrete
J 0
(-2450 1675);
PAINT ORANGE (-2450 1675);
DISPLAY INVISIBLE (-2450 1675);
FORCEPROP 1 LAST PATH I24
J 0
(-2500 1825);
DISPLAY 0.978723 (-2500 1825);
PAINT WHITE (-2500 1825);
DISPLAY INVISIBLE (-2500 1825);
FORCEPROP 2 LAST SEC 1
J 0
(-2500 1875);
DISPLAY 0.936170 (-2500 1875);
PAINT MONO (-2500 1875);
DISPLAY INVISIBLE (-2500 1875);
FORCEPROP 2 LAST SEC_TYPE 0402
J 0
(-2500 1875);
PAINT MONO (-2500 1875);
DISPLAY INVISIBLE (-2500 1875);
FORCEPROP 2 LAST ROOM PROC_SIDEBAND
J 0
(-2100 1775);
PAINT MONO (-2100 1775);
DISPLAY INVISIBLE (-2100 1775);
FORCEADD RES..1
(-2450 1475);
FORCEPROP 1 LAST LOCATION R3D23
J 0
(-2725 1500);
DISPLAY 0.617021 (-2725 1500);
PAINT AQUA (-2725 1500);
FORCEPROP 1 LAST PART_NUMBER G21796-294
J 0
(-2800 1425);
DISPLAY 0.617021 (-2800 1425);
PAINT BLUE (-2800 1425);
FORCEPROP 1 LASTPIN (-2550 1475) $PN 1
J 0
(-2538 1487);
DISPLAY 0.617021 (-2538 1487);
PAINT MONO (-2538 1487);
FORCEPROP 1 LAST PACK_TYPE 0402
J 0
(-2425 1425);
DISPLAY 0.617021 (-2425 1425);
PAINT SKYBLUE (-2425 1425);
FORCEPROP 1 LASTPIN (-2350 1475) $PN 2
J 0
(-2388 1487);
DISPLAY 0.617021 (-2388 1487);
PAINT MONO (-2388 1487);
FORCEPROP 1 LAST MATERIAL EMPTY
J 0
(-2225 1425);
DISPLAY 0.617021 (-2225 1425);
PAINT RED (-2225 1425);
FORCEPROP 1 LAST VALUE 240
J 2
(-2375 1525);
DISPLAY 0.617021 (-2375 1525);
PAINT SKYBLUE (-2375 1525);
FORCEPROP 1 LAST TOLERANCE 1.0%
J 0
(-2350 1525);
DISPLAY 0.617021 (-2350 1525);
PAINT SKYBLUE (-2350 1525);
FORCEPROP 1 LAST WATTAGE 1/16W
J 2
(-2100 1525);
DISPLAY 0.617021 (-2100 1525);
PAINT SKYBLUE (-2100 1525);
FORCEPROP 2 LAST CDS_LOCATION R3D23
J 0
(-2725 1500);
DISPLAY 0.617021 (-2725 1500);
PAINT AQUA (-2725 1500);
DISPLAY INVISIBLE (-2725 1500);
FORCEPROP 2 LAST BOM_COST PROC
J 0
(-2450 1475);
PAINT MONO (-2450 1475);
DISPLAY INVISIBLE (-2450 1475);
FORCEPROP 2 LAST CDS_LIB mstr_discrete
J 0
(-2450 1475);
PAINT ORANGE (-2450 1475);
DISPLAY INVISIBLE (-2450 1475);
FORCEPROP 1 LAST PATH I25
J 0
(-2500 1625);
DISPLAY 0.978723 (-2500 1625);
PAINT WHITE (-2500 1625);
DISPLAY INVISIBLE (-2500 1625);
FORCEPROP 2 LAST CDS_SEC 1
J 0
(-2500 1675);
DISPLAY 1.404255 (-2500 1675);
PAINT ORANGE (-2500 1675);
DISPLAY INVISIBLE (-2500 1675);
FORCEPROP 2 LAST $SEC 1
J 0
(-2500 1675);
DISPLAY 0.936170 (-2500 1675);
PAINT MONO (-2500 1675);
DISPLAY INVISIBLE (-2500 1675);
FORCEPROP 2 LAST ROOM PROC_SIDEBAND
J 0
(-2100 1575);
PAINT MONO (-2100 1575);
DISPLAY INVISIBLE (-2100 1575);
FORCEADD RES..1
(-2425 1275);
FORCEPROP 1 LAST LOCATION R3D26
J 0
(-2700 1300);
DISPLAY 0.617021 (-2700 1300);
PAINT AQUA (-2700 1300);
FORCEPROP 1 LAST PART_NUMBER G21796-294
J 0
(-2775 1225);
DISPLAY 0.617021 (-2775 1225);
PAINT BLUE (-2775 1225);
FORCEPROP 1 LASTPIN (-2525 1275) $PN 1
J 0
(-2513 1287);
DISPLAY 0.617021 (-2513 1287);
PAINT MONO (-2513 1287);
FORCEPROP 1 LAST VALUE 240
J 2
(-2350 1325);
DISPLAY 0.617021 (-2350 1325);
PAINT SKYBLUE (-2350 1325);
FORCEPROP 1 LASTPIN (-2325 1275) $PN 2
J 0
(-2363 1287);
DISPLAY 0.617021 (-2363 1287);
PAINT MONO (-2363 1287);
FORCEPROP 1 LAST TOLERANCE 1.0%
J 0
(-2325 1325);
DISPLAY 0.617021 (-2325 1325);
PAINT SKYBLUE (-2325 1325);
FORCEPROP 1 LAST PACK_TYPE 0402
J 0
(-2400 1225);
DISPLAY 0.617021 (-2400 1225);
PAINT SKYBLUE (-2400 1225);
FORCEPROP 1 LAST MATERIAL EMPTY
J 0
(-2200 1225);
DISPLAY 0.617021 (-2200 1225);
PAINT RED (-2200 1225);
FORCEPROP 1 LAST WATTAGE 1/16W
J 2
(-2050 1325);
DISPLAY 0.617021 (-2050 1325);
PAINT SKYBLUE (-2050 1325);
FORCEPROP 2 LAST CDS_LOCATION R3D26
J 0
(-2700 1300);
DISPLAY 0.617021 (-2700 1300);
PAINT AQUA (-2700 1300);
DISPLAY INVISIBLE (-2700 1300);
FORCEPROP 2 LAST BOM_COST PROC
J 0
(-2425 1275);
PAINT MONO (-2425 1275);
DISPLAY INVISIBLE (-2425 1275);
FORCEPROP 2 LAST CDS_LIB mstr_discrete
J 0
(-2425 1275);
PAINT ORANGE (-2425 1275);
DISPLAY INVISIBLE (-2425 1275);
FORCEPROP 2 LAST SEC_TYPE 0402
J 0
(-2475 1475);
PAINT MONO (-2475 1475);
DISPLAY INVISIBLE (-2475 1475);
FORCEPROP 2 LAST SEC 1
J 0
(-2475 1475);
DISPLAY 0.936170 (-2475 1475);
PAINT MONO (-2475 1475);
DISPLAY INVISIBLE (-2475 1475);
FORCEPROP 1 LAST PATH I28
J 0
(-2475 1425);
DISPLAY 0.978723 (-2475 1425);
PAINT WHITE (-2475 1425);
DISPLAY INVISIBLE (-2475 1425);
FORCEPROP 0 LAST ROOM PROC_SIDEBAND
J 0
(-2050 1425);
DISPLAY 1.021277 (-2050 1425);
PAINT ORANGE (-2050 1425);
DISPLAY INVISIBLE (-2050 1425);
FORCEADD RES..1
(-2475 4400);
FORCEPROP 1 LAST LOCATION R5D3
J 0
(-2750 4425);
DISPLAY 0.617021 (-2750 4425);
PAINT AQUA (-2750 4425);
FORCEPROP 1 LAST PART_NUMBER G21796-294
J 0
(-2825 4350);
DISPLAY 0.617021 (-2825 4350);
PAINT BLUE (-2825 4350);
FORCEPROP 1 LASTPIN (-2575 4400) $PN 1
J 0
(-2563 4412);
DISPLAY 0.617021 (-2563 4412);
PAINT MONO (-2563 4412);
FORCEPROP 1 LAST PACK_TYPE 0402
J 0
(-2450 4350);
DISPLAY 0.617021 (-2450 4350);
PAINT SKYBLUE (-2450 4350);
FORCEPROP 1 LAST VALUE 240
J 2
(-2400 4450);
DISPLAY 0.617021 (-2400 4450);
PAINT SKYBLUE (-2400 4450);
FORCEPROP 1 LASTPIN (-2375 4400) $PN 2
J 0
(-2413 4412);
DISPLAY 0.617021 (-2413 4412);
PAINT MONO (-2413 4412);
FORCEPROP 1 LAST TOLERANCE 1.0%
J 0
(-2375 4450);
DISPLAY 0.617021 (-2375 4450);
PAINT SKYBLUE (-2375 4450);
FORCEPROP 1 LAST MATERIAL CHIP
J 0
(-2250 4350);
DISPLAY 0.617021 (-2250 4350);
PAINT SKYBLUE (-2250 4350);
FORCEPROP 1 LAST WATTAGE 1/16W
J 2
(-2125 4450);
DISPLAY 0.617021 (-2125 4450);
PAINT SKYBLUE (-2125 4450);
FORCEPROP 2 LAST CDS_LOCATION R5D3
J 0
(-2750 4425);
DISPLAY 0.617021 (-2750 4425);
PAINT AQUA (-2750 4425);
DISPLAY INVISIBLE (-2750 4425);
FORCEPROP 1 LAST PATH I29
J 0
(-2525 4550);
DISPLAY 0.978723 (-2525 4550);
PAINT WHITE (-2525 4550);
DISPLAY INVISIBLE (-2525 4550);
FORCEPROP 2 LAST BOM_COST PROC
J 0
(-2475 4400);
PAINT MONO (-2475 4400);
DISPLAY INVISIBLE (-2475 4400);
FORCEPROP 2 LAST CDS_LIB mstr_discrete
J 0
(-2475 4400);
PAINT ORANGE (-2475 4400);
DISPLAY INVISIBLE (-2475 4400);
FORCEPROP 2 LAST ROOM PROC_SIDEBAND
J 0
(-2125 4500);
PAINT MONO (-2125 4500);
DISPLAY INVISIBLE (-2125 4500);
FORCEPROP 2 LAST SEC_TYPE 0402
J 0
(-2525 4600);
DISPLAY 1.021277 (-2525 4600);
PAINT ORANGE (-2525 4600);
DISPLAY INVISIBLE (-2525 4600);
FORCEPROP 2 LAST SEC 1
J 0
(-2525 4600);
DISPLAY 0.680851 (-2525 4600);
PAINT MONO (-2525 4600);
DISPLAY INVISIBLE (-2525 4600);
FORCEADD RES..1
(-500 3400);
FORCEPROP 1 LAST LOCATION R6D6
J 0
(-775 3425);
DISPLAY 0.617021 (-775 3425);
PAINT AQUA (-775 3425);
FORCEPROP 1 LAST PART_NUMBER G21796-294
J 0
(-850 3350);
DISPLAY 0.617021 (-850 3350);
PAINT BLUE (-850 3350);
FORCEPROP 1 LAST WATTAGE 1/16W
J 2
(-700 3300);
DISPLAY 0.617021 (-700 3300);
PAINT SKYBLUE (-700 3300);
FORCEPROP 1 LASTPIN (-600 3400) $PN 1
J 0
(-588 3412);
DISPLAY 0.617021 (-588 3412);
PAINT MONO (-588 3412);
FORCEPROP 1 LAST VALUE 240
J 2
(-425 3450);
DISPLAY 0.617021 (-425 3450);
PAINT SKYBLUE (-425 3450);
FORCEPROP 1 LAST TOLERANCE 1.0%
J 0
(-400 3450);
DISPLAY 0.617021 (-400 3450);
PAINT SKYBLUE (-400 3450);
FORCEPROP 1 LAST PACK_TYPE 0402
J 0
(-475 3350);
DISPLAY 0.617021 (-475 3350);
PAINT SKYBLUE (-475 3350);
FORCEPROP 1 LASTPIN (-400 3400) $PN 2
J 0
(-438 3412);
DISPLAY 0.617021 (-438 3412);
PAINT MONO (-438 3412);
FORCEPROP 1 LAST MATERIAL CHIP
J 0
(-275 3350);
DISPLAY 0.617021 (-275 3350);
PAINT RED (-275 3350);
FORCEPROP 2 LAST CDS_LOCATION R6D6
J 0
(-775 3425);
DISPLAY 0.617021 (-775 3425);
PAINT AQUA (-775 3425);
DISPLAY INVISIBLE (-775 3425);
FORCEPROP 1 LAST PATH I3
J 0
(-550 3550);
DISPLAY 0.978723 (-550 3550);
PAINT WHITE (-550 3550);
DISPLAY INVISIBLE (-550 3550);
FORCEPROP 2 LAST SEC_TYPE 0402
J 0
(-550 3600);
PAINT MONO (-550 3600);
DISPLAY INVISIBLE (-550 3600);
FORCEPROP 2 LAST SEC 1
J 0
(-550 3600);
DISPLAY 0.936170 (-550 3600);
PAINT MONO (-550 3600);
DISPLAY INVISIBLE (-550 3600);
FORCEPROP 2 LAST CDS_LIB mstr_discrete
J 0
(-500 3400);
PAINT ORANGE (-500 3400);
DISPLAY INVISIBLE (-500 3400);
FORCEPROP 2 LAST BOM_COST PROC
J 0
(-500 3400);
PAINT MONO (-500 3400);
DISPLAY INVISIBLE (-500 3400);
FORCEPROP 2 LAST ROOM PROC_SIDEBAND
J 0
(-400 3500);
PAINT MONO (-400 3500);
DISPLAY INVISIBLE (-400 3500);
FORCEADD PVCCIO_CPU0..1
(-2975 4550);
FORCEPROP 3 LASTPIN (-2975 4500) SIG_NAME PVCCIO_CPU0\g
J 0
(-2965 4510);
DISPLAY 0.659574 (-2965 4510);
PAINT MONO (-2965 4510);
DISPLAY INVISIBLE (-2965 4510);
FORCEPROP 1 LAST VOLTAGE 1.1V
J 0
(-3020 4507);
DISPLAY 0.340426 (-3020 4507);
PAINT SKYBLUE (-3020 4507);
DISPLAY INVISIBLE (-3020 4507);
FORCEPROP 1 LAST BODY_TYPE PLUMBING
J 0
(-3020 4507);
DISPLAY 0.340426 (-3020 4507);
PAINT GREEN (-3020 4507);
DISPLAY INVISIBLE (-3020 4507);
FORCEPROP 2 LAST CDS_LIB mstr_symbols
J 0
(-2975 4550);
PAINT ORANGE (-2975 4550);
DISPLAY INVISIBLE (-2975 4550);
FORCEPROP 1 LAST PATH I30
J 0
(-2925 4575);
DISPLAY 0.872340 (-2925 4575);
PAINT AQUA (-2925 4575);
DISPLAY INVISIBLE (-2925 4575);
FORCEPROP 1 LAST HDL_POWER PVCCIO_CPU0
J 1
(-2975 4600);
DISPLAY 0.872340 (-2975 4600);
PAINT GREEN (-2975 4600);
DISPLAY INVISIBLE (-2975 4600);
FORCEADD RES..1
(-2475 4200);
FORCEPROP 1 LAST LOCATION R6D7
J 0
(-2750 4225);
DISPLAY 0.617021 (-2750 4225);
PAINT AQUA (-2750 4225);
FORCEPROP 1 LAST PART_NUMBER G21796-294
J 0
(-2825 4150);
DISPLAY 0.617021 (-2825 4150);
PAINT BLUE (-2825 4150);
FORCEPROP 1 LASTPIN (-2575 4200) $PN 1
J 0
(-2563 4212);
DISPLAY 0.617021 (-2563 4212);
PAINT MONO (-2563 4212);
FORCEPROP 1 LAST VALUE 240
J 2
(-2425 4250);
DISPLAY 0.617021 (-2425 4250);
PAINT SKYBLUE (-2425 4250);
FORCEPROP 1 LAST PACK_TYPE 0402
J 0
(-2450 4150);
DISPLAY 0.617021 (-2450 4150);
PAINT SKYBLUE (-2450 4150);
FORCEPROP 1 LASTPIN (-2375 4200) $PN 2
J 0
(-2413 4212);
DISPLAY 0.617021 (-2413 4212);
PAINT MONO (-2413 4212);
FORCEPROP 1 LAST TOLERANCE 1.0%
J 0
(-2375 4250);
DISPLAY 0.617021 (-2375 4250);
PAINT SKYBLUE (-2375 4250);
FORCEPROP 1 LAST MATERIAL EMPTY
J 0
(-2250 4150);
DISPLAY 0.617021 (-2250 4150);
PAINT SKYBLUE (-2250 4150);
FORCEPROP 1 LAST WATTAGE 1/16W
J 2
(-2125 4250);
DISPLAY 0.617021 (-2125 4250);
PAINT SKYBLUE (-2125 4250);
FORCEPROP 2 LAST CDS_LOCATION R6D7
J 0
(-2750 4225);
DISPLAY 0.617021 (-2750 4225);
PAINT AQUA (-2750 4225);
DISPLAY INVISIBLE (-2750 4225);
FORCEPROP 2 LAST CDS_LIB mstr_discrete
J 0
(-2475 4200);
PAINT ORANGE (-2475 4200);
DISPLAY INVISIBLE (-2475 4200);
FORCEPROP 2 LAST BOM_COST PROC
J 0
(-2475 4200);
PAINT MONO (-2475 4200);
DISPLAY INVISIBLE (-2475 4200);
FORCEPROP 1 LAST PATH I31
J 0
(-2525 4350);
DISPLAY 0.978723 (-2525 4350);
PAINT WHITE (-2525 4350);
DISPLAY INVISIBLE (-2525 4350);
FORCEPROP 2 LAST SEC 1
J 0
(-2525 4400);
DISPLAY 0.680851 (-2525 4400);
PAINT MONO (-2525 4400);
DISPLAY INVISIBLE (-2525 4400);
FORCEPROP 2 LAST SEC_TYPE 0402
J 0
(-2525 4400);
DISPLAY 1.021277 (-2525 4400);
PAINT ORANGE (-2525 4400);
DISPLAY INVISIBLE (-2525 4400);
FORCEPROP 2 LAST ROOM PROC_SIDEBAND
J 0
(-2125 4300);
PAINT MONO (-2125 4300);
DISPLAY INVISIBLE (-2125 4300);
FORCEADD RES..1
(-2475 4000);
FORCEPROP 1 LAST LOCATION R5D4
J 0
(-2750 4025);
DISPLAY 0.617021 (-2750 4025);
PAINT AQUA (-2750 4025);
FORCEPROP 1 LAST PART_NUMBER G21796-294
J 0
(-2825 3950);
DISPLAY 0.617021 (-2825 3950);
PAINT BLUE (-2825 3950);
FORCEPROP 1 LASTPIN (-2575 4000) $PN 1
J 0
(-2563 4012);
DISPLAY 0.617021 (-2563 4012);
PAINT MONO (-2563 4012);
FORCEPROP 1 LASTPIN (-2375 4000) $PN 2
J 0
(-2413 4012);
DISPLAY 0.617021 (-2413 4012);
PAINT MONO (-2413 4012);
FORCEPROP 1 LAST PACK_TYPE 0402
J 0
(-2375 3950);
DISPLAY 0.617021 (-2375 3950);
PAINT SKYBLUE (-2375 3950);
FORCEPROP 1 LAST TOLERANCE 1.0%
J 0
(-2375 4050);
DISPLAY 0.617021 (-2375 4050);
PAINT SKYBLUE (-2375 4050);
FORCEPROP 1 LAST MATERIAL EMPTY
J 0
(-2250 3950);
DISPLAY 0.617021 (-2250 3950);
PAINT SKYBLUE (-2250 3950);
FORCEPROP 1 LAST WATTAGE 1/16W
J 2
(-2125 4050);
DISPLAY 0.617021 (-2125 4050);
PAINT SKYBLUE (-2125 4050);
FORCEPROP 1 LAST VALUE 240
J 2
(-2000 4050);
DISPLAY 0.617021 (-2000 4050);
PAINT SKYBLUE (-2000 4050);
FORCEPROP 2 LAST CDS_LOCATION R5D4
J 0
(-2750 4025);
DISPLAY 0.617021 (-2750 4025);
PAINT AQUA (-2750 4025);
DISPLAY INVISIBLE (-2750 4025);
FORCEPROP 2 LAST BOM_COST PROC
J 0
(-2475 4000);
PAINT MONO (-2475 4000);
DISPLAY INVISIBLE (-2475 4000);
FORCEPROP 2 LAST CDS_LIB mstr_discrete
J 0
(-2475 4000);
PAINT ORANGE (-2475 4000);
DISPLAY INVISIBLE (-2475 4000);
FORCEPROP 1 LAST PATH I32
J 0
(-2525 4150);
DISPLAY 0.978723 (-2525 4150);
PAINT WHITE (-2525 4150);
DISPLAY INVISIBLE (-2525 4150);
FORCEPROP 2 LAST SEC 1
J 0
(-2525 4200);
DISPLAY 0.680851 (-2525 4200);
PAINT MONO (-2525 4200);
DISPLAY INVISIBLE (-2525 4200);
FORCEPROP 2 LAST SEC_TYPE 0402
J 0
(-2525 4200);
DISPLAY 1.021277 (-2525 4200);
PAINT ORANGE (-2525 4200);
DISPLAY INVISIBLE (-2525 4200);
FORCEPROP 2 LAST ROOM PROC_SIDEBAND
J 0
(-2125 4100);
PAINT MONO (-2125 4100);
DISPLAY INVISIBLE (-2125 4100);
FORCEADD RES..1
(-2500 3800);
FORCEPROP 1 LAST LOCATION R6D13
J 0
(-2775 3825);
DISPLAY 0.617021 (-2775 3825);
PAINT AQUA (-2775 3825);
FORCEPROP 1 LAST PART_NUMBER G21796-294
J 0
(-2850 3750);
DISPLAY 0.617021 (-2850 3750);
PAINT BLUE (-2850 3750);
FORCEPROP 1 LASTPIN (-2600 3800) $PN 1
J 0
(-2588 3812);
DISPLAY 0.617021 (-2588 3812);
PAINT MONO (-2588 3812);
FORCEPROP 1 LASTPIN (-2400 3800) $PN 2
J 0
(-2438 3812);
DISPLAY 0.617021 (-2438 3812);
PAINT MONO (-2438 3812);
FORCEPROP 1 LAST VALUE 240
J 2
(-2450 3850);
DISPLAY 0.617021 (-2450 3850);
PAINT SKYBLUE (-2450 3850);
FORCEPROP 1 LAST TOLERANCE 1.0%
J 0
(-2400 3850);
DISPLAY 0.617021 (-2400 3850);
PAINT SKYBLUE (-2400 3850);
FORCEPROP 1 LAST MATERIAL EMPTY
J 0
(-2275 3750);
DISPLAY 0.617021 (-2275 3750);
PAINT RED (-2275 3750);
FORCEPROP 1 LAST WATTAGE 1/16W
J 2
(-2125 3850);
DISPLAY 0.617021 (-2125 3850);
PAINT SKYBLUE (-2125 3850);
FORCEPROP 1 LAST PACK_TYPE 0402
J 0
(-2125 3750);
DISPLAY 0.617021 (-2125 3750);
PAINT SKYBLUE (-2125 3750);
FORCEPROP 2 LAST CDS_LOCATION R6D13
J 0
(-2775 3825);
DISPLAY 0.617021 (-2775 3825);
PAINT AQUA (-2775 3825);
DISPLAY INVISIBLE (-2775 3825);
FORCEPROP 2 LAST BOM_COST PROC
J 0
(-2500 3800);
PAINT MONO (-2500 3800);
DISPLAY INVISIBLE (-2500 3800);
FORCEPROP 2 LAST CDS_LIB mstr_discrete
J 0
(-2500 3800);
PAINT ORANGE (-2500 3800);
DISPLAY INVISIBLE (-2500 3800);
FORCEPROP 1 LAST PATH I33
J 0
(-2550 3950);
DISPLAY 0.978723 (-2550 3950);
PAINT WHITE (-2550 3950);
DISPLAY INVISIBLE (-2550 3950);
FORCEPROP 2 LAST SEC 1
J 0
(-2550 4000);
DISPLAY 0.680851 (-2550 4000);
PAINT MONO (-2550 4000);
DISPLAY INVISIBLE (-2550 4000);
FORCEPROP 2 LAST SEC_TYPE 0402
J 0
(-2550 4000);
DISPLAY 1.021277 (-2550 4000);
PAINT ORANGE (-2550 4000);
DISPLAY INVISIBLE (-2550 4000);
FORCEPROP 0 LAST ROOM PROC_SIDEBAND
J 0
(-2125 3950);
DISPLAY 1.021277 (-2125 3950);
PAINT ORANGE (-2125 3950);
DISPLAY INVISIBLE (-2125 3950);
FORCEADD RES..1
(-500 3200);
FORCEPROP 1 LAST LOCATION R4P1
J 0
(-775 3225);
DISPLAY 0.617021 (-775 3225);
PAINT AQUA (-775 3225);
FORCEPROP 1 LAST PART_NUMBER G21796-294
J 0
(-850 3150);
DISPLAY 0.617021 (-850 3150);
PAINT BLUE (-850 3150);
FORCEPROP 1 LAST WATTAGE 1/16W
J 2
(-700 3100);
DISPLAY 0.617021 (-700 3100);
PAINT SKYBLUE (-700 3100);
FORCEPROP 1 LASTPIN (-600 3200) $PN 1
J 0
(-588 3212);
DISPLAY 0.617021 (-588 3212);
PAINT MONO (-588 3212);
FORCEPROP 1 LAST VALUE 240
J 2
(-425 3250);
DISPLAY 0.617021 (-425 3250);
PAINT SKYBLUE (-425 3250);
FORCEPROP 1 LASTPIN (-400 3200) $PN 2
J 0
(-438 3212);
DISPLAY 0.617021 (-438 3212);
PAINT MONO (-438 3212);
FORCEPROP 1 LAST TOLERANCE 1.0%
J 0
(-400 3250);
DISPLAY 0.617021 (-400 3250);
PAINT SKYBLUE (-400 3250);
FORCEPROP 1 LAST PACK_TYPE 0402
J 0
(-475 3150);
DISPLAY 0.617021 (-475 3150);
PAINT SKYBLUE (-475 3150);
FORCEPROP 1 LAST MATERIAL EMPTY
J 0
(-275 3150);
DISPLAY 0.617021 (-275 3150);
PAINT RED (-275 3150);
FORCEPROP 2 LAST CDS_LOCATION R4P1
J 0
(-775 3225);
DISPLAY 0.617021 (-775 3225);
PAINT AQUA (-775 3225);
DISPLAY INVISIBLE (-775 3225);
FORCEPROP 1 LAST PATH I4
J 0
(-550 3350);
DISPLAY 0.978723 (-550 3350);
PAINT WHITE (-550 3350);
DISPLAY INVISIBLE (-550 3350);
FORCEPROP 2 LAST SEC 1
J 0
(-550 3400);
DISPLAY 0.936170 (-550 3400);
PAINT MONO (-550 3400);
DISPLAY INVISIBLE (-550 3400);
FORCEPROP 2 LAST SEC_TYPE 0402
J 0
(-550 3400);
PAINT MONO (-550 3400);
DISPLAY INVISIBLE (-550 3400);
FORCEPROP 2 LAST BOM_COST PROC
J 2
(-500 3200);
PAINT MONO (-500 3200);
DISPLAY INVISIBLE (-500 3200);
FORCEPROP 2 LAST CDS_LIB mstr_discrete
J 0
(-500 3200);
PAINT ORANGE (-500 3200);
DISPLAY INVISIBLE (-500 3200);
FORCEPROP 2 LAST ROOM PROC_SIDEBAND
J 0
(-400 3300);
PAINT MONO (-400 3300);
DISPLAY INVISIBLE (-400 3300);
FORCEADD OFFPAGE..1
R 2
(525 4400);
FORCEPROP 2 LAST $XR0 21 
J 0
(711 4400);
DISPLAY 0.638298 (711 4400);
PAINT MONO (711 4400);
FORCEPROP 2 LAST PATH I45
J 2
(325 4450);
DISPLAY 1.021277 (325 4450);
PAINT ORANGE (325 4450);
DISPLAY INVISIBLE (325 4450);
FORCEPROP 1 LAST COMMENT_BODY TRUE
J 2
(400 4300);
DISPLAY 0.872340 (400 4300);
PAINT GREEN (400 4300);
DISPLAY INVISIBLE (400 4300);
FORCEPROP 1 LAST OFFPAGE TRUE
J 2
(200 4275);
DISPLAY 0.872340 (200 4275);
PAINT GREEN (200 4275);
DISPLAY INVISIBLE (200 4275);
FORCEPROP 2 LAST CDS_LIB mstr_standard
J 2
(525 4400);
PAINT ORANGE (525 4400);
DISPLAY INVISIBLE (525 4400);
FORCEADD OFFPAGE..1
R 2
(525 4200);
FORCEPROP 2 LAST $XR0 21 
J 0
(711 4200);
DISPLAY 0.638298 (711 4200);
PAINT MONO (711 4200);
FORCEPROP 1 LAST OFFPAGE TRUE
J 2
(200 4075);
DISPLAY 0.872340 (200 4075);
PAINT GREEN (200 4075);
DISPLAY INVISIBLE (200 4075);
FORCEPROP 2 LAST PATH I46
J 2
(325 4250);
DISPLAY 1.021277 (325 4250);
PAINT ORANGE (325 4250);
DISPLAY INVISIBLE (325 4250);
FORCEPROP 1 LAST COMMENT_BODY TRUE
J 2
(400 4100);
DISPLAY 0.872340 (400 4100);
PAINT GREEN (400 4100);
DISPLAY INVISIBLE (400 4100);
FORCEPROP 2 LAST CDS_LIB mstr_standard
J 2
(525 4200);
PAINT ORANGE (525 4200);
DISPLAY INVISIBLE (525 4200);
FORCEADD RES..1
(-300 4400);
FORCEPROP 1 LAST LOCATION R6D15
J 0
(-575 4425);
DISPLAY 0.617021 (-575 4425);
PAINT AQUA (-575 4425);
FORCEPROP 1 LAST PART_NUMBER G21796-294
J 0
(-650 4350);
DISPLAY 0.617021 (-650 4350);
PAINT BLUE (-650 4350);
FORCEPROP 1 LASTPIN (-400 4400) $PN 1
J 0
(-388 4412);
DISPLAY 0.617021 (-388 4412);
PAINT ORANGE (-388 4412);
FORCEPROP 1 LAST VALUE 240
J 2
(-225 4450);
DISPLAY 0.617021 (-225 4450);
PAINT SKYBLUE (-225 4450);
FORCEPROP 1 LAST PACK_TYPE 0402
J 0
(-275 4350);
DISPLAY 0.617021 (-275 4350);
PAINT SKYBLUE (-275 4350);
FORCEPROP 1 LAST TOLERANCE 1.0%
J 0
(-200 4450);
DISPLAY 0.617021 (-200 4450);
PAINT SKYBLUE (-200 4450);
FORCEPROP 1 LASTPIN (-200 4400) $PN 2
J 0
(-238 4412);
DISPLAY 0.617021 (-238 4412);
PAINT ORANGE (-238 4412);
FORCEPROP 1 LAST MATERIAL EMPTY
J 0
(-75 4350);
DISPLAY 0.617021 (-75 4350);
PAINT RED (-75 4350);
FORCEPROP 1 LAST WATTAGE 1/16W
J 2
(75 4450);
DISPLAY 0.617021 (75 4450);
PAINT SKYBLUE (75 4450);
FORCEPROP 2 LAST CDS_LOCATION R6D15
J 0
(-575 4425);
DISPLAY 0.617021 (-575 4425);
PAINT AQUA (-575 4425);
DISPLAY INVISIBLE (-575 4425);
FORCEPROP 2 LAST BOM_COST PROC
J 0
(-300 4400);
PAINT MONO (-300 4400);
DISPLAY INVISIBLE (-300 4400);
FORCEPROP 2 LAST CDS_LIB mstr_discrete
J 0
(-300 4400);
PAINT ORANGE (-300 4400);
DISPLAY INVISIBLE (-300 4400);
FORCEPROP 1 LAST PATH I48
J 0
(-350 4550);
DISPLAY 0.978723 (-350 4550);
PAINT WHITE (-350 4550);
DISPLAY INVISIBLE (-350 4550);
FORCEPROP 2 LAST SEC_TYPE 0402
J 0
(-350 4600);
DISPLAY 1.021277 (-350 4600);
PAINT ORANGE (-350 4600);
DISPLAY INVISIBLE (-350 4600);
FORCEPROP 2 LAST SEC 1
J 0
(-350 4600);
DISPLAY 0.680851 (-350 4600);
PAINT MONO (-350 4600);
DISPLAY INVISIBLE (-350 4600);
FORCEPROP 2 LAST ROOM PROC_SIDEBAND
J 0
(75 4500);
PAINT MONO (75 4500);
DISPLAY INVISIBLE (75 4500);
FORCEADD RES..1
(-300 4200);
FORCEPROP 1 LAST LOCATION R6D10
J 0
(-575 4225);
DISPLAY 0.617021 (-575 4225);
PAINT AQUA (-575 4225);
FORCEPROP 1 LAST PART_NUMBER G21796-294
J 0
(-650 4150);
DISPLAY 0.617021 (-650 4150);
PAINT BLUE (-650 4150);
FORCEPROP 1 LASTPIN (-400 4200) $PN 1
J 0
(-388 4212);
DISPLAY 0.617021 (-388 4212);
PAINT MONO (-388 4212);
FORCEPROP 1 LAST VALUE 240
J 2
(-225 4250);
DISPLAY 0.617021 (-225 4250);
PAINT SKYBLUE (-225 4250);
FORCEPROP 1 LAST PACK_TYPE 0402
J 0
(-275 4150);
DISPLAY 0.617021 (-275 4150);
PAINT SKYBLUE (-275 4150);
FORCEPROP 1 LASTPIN (-200 4200) $PN 2
J 0
(-238 4212);
DISPLAY 0.617021 (-238 4212);
PAINT MONO (-238 4212);
FORCEPROP 1 LAST TOLERANCE 1.0%
J 0
(-200 4250);
DISPLAY 0.617021 (-200 4250);
PAINT SKYBLUE (-200 4250);
FORCEPROP 1 LAST MATERIAL EMPTY
J 0
(-75 4150);
DISPLAY 0.617021 (-75 4150);
PAINT RED (-75 4150);
FORCEPROP 1 LAST WATTAGE 1/16W
J 2
(75 4250);
DISPLAY 0.617021 (75 4250);
PAINT SKYBLUE (75 4250);
FORCEPROP 2 LAST CDS_LOCATION R6D10
J 0
(-575 4225);
DISPLAY 0.617021 (-575 4225);
PAINT AQUA (-575 4225);
DISPLAY INVISIBLE (-575 4225);
FORCEPROP 2 LAST BOM_COST PROC
J 0
(-300 4200);
PAINT MONO (-300 4200);
DISPLAY INVISIBLE (-300 4200);
FORCEPROP 2 LAST CDS_LIB mstr_discrete
J 0
(-300 4200);
PAINT ORANGE (-300 4200);
DISPLAY INVISIBLE (-300 4200);
FORCEPROP 1 LAST PATH I49
J 0
(-350 4350);
DISPLAY 0.978723 (-350 4350);
PAINT WHITE (-350 4350);
DISPLAY INVISIBLE (-350 4350);
FORCEPROP 2 LAST SEC_TYPE 0402
J 0
(-350 4400);
DISPLAY 1.021277 (-350 4400);
PAINT ORANGE (-350 4400);
DISPLAY INVISIBLE (-350 4400);
FORCEPROP 2 LAST SEC 1
J 0
(-350 4400);
DISPLAY 0.680851 (-350 4400);
PAINT MONO (-350 4400);
DISPLAY INVISIBLE (-350 4400);
FORCEPROP 2 LAST ROOM PROC_SIDEBAND
J 0
(75 4300);
PAINT MONO (75 4300);
DISPLAY INVISIBLE (75 4300);
FORCEADD GND..1
(-900 2600);
FORCEPROP 3 LASTPIN (-900 2650) SIG_NAME GND\g
J 0
(-890 2660);
DISPLAY 0.659574 (-890 2660);
PAINT MONO (-890 2660);
DISPLAY INVISIBLE (-890 2660);
FORCEPROP 1 LAST SIZE 1B
J 0
(-825 2550);
DISPLAY 0.872340 (-825 2550);
PAINT GREEN (-825 2550);
DISPLAY INVISIBLE (-825 2550);
FORCEPROP 1 LAST BODY_TYPE PLUMBING
J 0
(-945 2557);
DISPLAY 0.340426 (-945 2557);
PAINT GREEN (-945 2557);
DISPLAY INVISIBLE (-945 2557);
FORCEPROP 1 LAST VOLTAGE 0
J 0
(-900 2600);
PAINT SKYBLUE (-900 2600);
DISPLAY INVISIBLE (-900 2600);
FORCEPROP 2 LAST CDS_LIB mstr_symbols
J 0
(-900 2600);
PAINT ORANGE (-900 2600);
DISPLAY INVISIBLE (-900 2600);
FORCEPROP 1 LAST HDL_POWER GND
J 0
(-900 2750);
DISPLAY 0.872340 (-900 2750);
PAINT GREEN (-900 2750);
DISPLAY INVISIBLE (-900 2750);
FORCEPROP 1 LAST PATH I5
J 0
(-825 2600);
DISPLAY 0.872340 (-825 2600);
PAINT AQUA (-825 2600);
DISPLAY INVISIBLE (-825 2600);
FORCEADD PVCCIO_CPU0..1
(-825 4625);
FORCEPROP 3 LASTPIN (-825 4575) SIG_NAME PVCCIO_CPU0\g
J 0
(-815 4585);
DISPLAY 0.659574 (-815 4585);
PAINT MONO (-815 4585);
DISPLAY INVISIBLE (-815 4585);
FORCEPROP 1 LAST VOLTAGE 1.1V
J 0
(-870 4582);
DISPLAY 0.340426 (-870 4582);
PAINT SKYBLUE (-870 4582);
DISPLAY INVISIBLE (-870 4582);
FORCEPROP 1 LAST BODY_TYPE PLUMBING
J 0
(-870 4582);
DISPLAY 0.340426 (-870 4582);
PAINT GREEN (-870 4582);
DISPLAY INVISIBLE (-870 4582);
FORCEPROP 1 LAST HDL_POWER PVCCIO_CPU0
J 1
(-825 4675);
DISPLAY 0.872340 (-825 4675);
PAINT GREEN (-825 4675);
DISPLAY INVISIBLE (-825 4675);
FORCEPROP 1 LAST PATH I51
J 0
(-775 4650);
DISPLAY 0.872340 (-775 4650);
PAINT AQUA (-775 4650);
DISPLAY INVISIBLE (-775 4650);
FORCEPROP 2 LAST CDS_LIB mstr_symbols
J 0
(-825 4625);
PAINT ORANGE (-825 4625);
DISPLAY INVISIBLE (-825 4625);
FORCEADD RES..1
(-2475 3600);
FORCEPROP 1 LAST LOCATION R6D14
J 0
(-2775 3625);
DISPLAY 0.617021 (-2775 3625);
PAINT AQUA (-2775 3625);
FORCEPROP 1 LAST PART_NUMBER G21796-294
J 0
(-2825 3550);
DISPLAY 0.617021 (-2825 3550);
PAINT BLUE (-2825 3550);
FORCEPROP 1 LASTPIN (-2575 3600) $PN 1
J 0
(-2563 3612);
DISPLAY 0.617021 (-2563 3612);
PAINT ORANGE (-2563 3612);
FORCEPROP 1 LAST PACK_TYPE 0402
J 0
(-2450 3550);
DISPLAY 0.617021 (-2450 3550);
PAINT SKYBLUE (-2450 3550);
FORCEPROP 1 LAST MATERIAL EMPTY
J 0
(-2250 3550);
DISPLAY 0.617021 (-2250 3550);
PAINT RED (-2250 3550);
FORCEPROP 1 LAST VALUE 240
J 2
(-2425 3650);
DISPLAY 0.617021 (-2425 3650);
PAINT SKYBLUE (-2425 3650);
FORCEPROP 1 LASTPIN (-2375 3600) $PN 2
J 0
(-2413 3612);
DISPLAY 0.617021 (-2413 3612);
PAINT ORANGE (-2413 3612);
FORCEPROP 1 LAST TOLERANCE 1.0%
J 0
(-2375 3650);
DISPLAY 0.617021 (-2375 3650);
PAINT SKYBLUE (-2375 3650);
FORCEPROP 1 LAST WATTAGE 1/16W
J 2
(-2125 3650);
DISPLAY 0.617021 (-2125 3650);
PAINT SKYBLUE (-2125 3650);
FORCEPROP 2 LAST CDS_LOCATION R6D14
J 0
(-2775 3625);
DISPLAY 0.617021 (-2775 3625);
PAINT AQUA (-2775 3625);
DISPLAY INVISIBLE (-2775 3625);
FORCEPROP 2 LAST CDS_LIB mstr_discrete
J 0
(-2475 3600);
PAINT ORANGE (-2475 3600);
DISPLAY INVISIBLE (-2475 3600);
FORCEPROP 2 LAST BOM_COST PROC
J 0
(-2475 3600);
PAINT MONO (-2475 3600);
DISPLAY INVISIBLE (-2475 3600);
FORCEPROP 2 LAST SEC 1
J 0
(-2525 3800);
DISPLAY 0.680851 (-2525 3800);
PAINT MONO (-2525 3800);
DISPLAY INVISIBLE (-2525 3800);
FORCEPROP 1 LAST PATH I52
J 0
(-2525 3750);
DISPLAY 0.978723 (-2525 3750);
PAINT WHITE (-2525 3750);
DISPLAY INVISIBLE (-2525 3750);
FORCEPROP 2 LAST SEC_TYPE 0402
J 0
(-2525 3800);
DISPLAY 1.021277 (-2525 3800);
PAINT ORANGE (-2525 3800);
DISPLAY INVISIBLE (-2525 3800);
FORCEPROP 2 LAST ROOM PROC_SIDEBAND
J 0
(-2125 3700);
PAINT MONO (-2125 3700);
DISPLAY INVISIBLE (-2125 3700);
FORCEADD RES..1
(-2500 3400);
FORCEPROP 1 LAST LOCATION R4P14
J 0
(-2750 3425);
DISPLAY 0.617021 (-2750 3425);
PAINT AQUA (-2750 3425);
FORCEPROP 1 LAST PART_NUMBER G21796-294
J 0
(-2850 3350);
DISPLAY 0.617021 (-2850 3350);
PAINT BLUE (-2850 3350);
FORCEPROP 1 LASTPIN (-2600 3400) $PN 1
J 0
(-2588 3412);
DISPLAY 0.617021 (-2588 3412);
PAINT ORANGE (-2588 3412);
FORCEPROP 1 LAST VALUE 240
J 2
(-2425 3450);
DISPLAY 0.617021 (-2425 3450);
PAINT SKYBLUE (-2425 3450);
FORCEPROP 1 LAST PACK_TYPE 0402
J 0
(-2475 3350);
DISPLAY 0.617021 (-2475 3350);
PAINT SKYBLUE (-2475 3350);
FORCEPROP 1 LASTPIN (-2400 3400) $PN 2
J 0
(-2438 3412);
DISPLAY 0.617021 (-2438 3412);
PAINT ORANGE (-2438 3412);
FORCEPROP 1 LAST TOLERANCE 1.0%
J 0
(-2400 3450);
DISPLAY 0.617021 (-2400 3450);
PAINT SKYBLUE (-2400 3450);
FORCEPROP 1 LAST MATERIAL CHIP
J 0
(-2275 3350);
DISPLAY 0.617021 (-2275 3350);
PAINT SKYBLUE (-2275 3350);
FORCEPROP 1 LAST WATTAGE 1/16W
J 2
(-2125 3450);
DISPLAY 0.617021 (-2125 3450);
PAINT SKYBLUE (-2125 3450);
FORCEPROP 2 LAST CDS_LOCATION R4P14
J 0
(-2750 3425);
DISPLAY 0.617021 (-2750 3425);
PAINT AQUA (-2750 3425);
DISPLAY INVISIBLE (-2750 3425);
FORCEPROP 2 LAST CDS_LIB mstr_discrete
J 0
(-2500 3400);
PAINT ORANGE (-2500 3400);
DISPLAY INVISIBLE (-2500 3400);
FORCEPROP 2 LAST BOM_COST PROC
J 0
(-2500 3400);
PAINT MONO (-2500 3400);
DISPLAY INVISIBLE (-2500 3400);
FORCEPROP 1 LAST PATH I53
J 0
(-2550 3550);
DISPLAY 0.978723 (-2550 3550);
PAINT WHITE (-2550 3550);
DISPLAY INVISIBLE (-2550 3550);
FORCEPROP 0 LAST ROOM PROC_SIDEBAND
J 0
(-2125 3550);
DISPLAY 1.021277 (-2125 3550);
PAINT ORANGE (-2125 3550);
DISPLAY INVISIBLE (-2125 3550);
FORCEPROP 2 LAST SEC_TYPE 0402
J 0
(-2550 3600);
DISPLAY 1.021277 (-2550 3600);
PAINT ORANGE (-2550 3600);
DISPLAY INVISIBLE (-2550 3600);
FORCEPROP 2 LAST SEC 1
J 0
(-2550 3600);
DISPLAY 0.680851 (-2550 3600);
PAINT MONO (-2550 3600);
DISPLAY INVISIBLE (-2550 3600);
FORCEADD OFFPAGE..2
(-1300 3600);
FORCEPROP 2 LAST $XR0 21 
J 0
(-1111 3600);
DISPLAY 0.638298 (-1111 3600);
PAINT MONO (-1111 3600);
FORCEPROP 1 LAST COMMENT_BODY TRUE
J 0
(-1345 3505);
DISPLAY 1.170213 (-1345 3505);
PAINT GREEN (-1345 3505);
DISPLAY INVISIBLE (-1345 3505);
FORCEPROP 2 LAST CDS_LIB mstr_standard
J 0
(-1300 3600);
PAINT ORANGE (-1300 3600);
DISPLAY INVISIBLE (-1300 3600);
FORCEPROP 2 LAST PATH I54
J 0
(-1125 3675);
DISPLAY 1.021277 (-1125 3675);
PAINT ORANGE (-1125 3675);
DISPLAY INVISIBLE (-1125 3675);
FORCEPROP 1 LAST OFFPAGE TRUE
J 0
(-975 3475);
PAINT GREEN (-975 3475);
DISPLAY INVISIBLE (-975 3475);
FORCEADD OFFPAGE..2
(-1300 3400);
FORCEPROP 2 LAST $XR0 21 
J 0
(-1111 3400);
DISPLAY 0.638298 (-1111 3400);
PAINT MONO (-1111 3400);
FORCEPROP 1 LAST COMMENT_BODY TRUE
J 0
(-1345 3305);
DISPLAY 1.170213 (-1345 3305);
PAINT GREEN (-1345 3305);
DISPLAY INVISIBLE (-1345 3305);
FORCEPROP 2 LAST CDS_LIB mstr_standard
J 0
(-1300 3400);
PAINT ORANGE (-1300 3400);
DISPLAY INVISIBLE (-1300 3400);
FORCEPROP 2 LAST PATH I55
J 0
(-1125 3475);
DISPLAY 1.021277 (-1125 3475);
PAINT ORANGE (-1125 3475);
DISPLAY INVISIBLE (-1125 3475);
FORCEPROP 1 LAST OFFPAGE TRUE
J 0
(-975 3275);
PAINT GREEN (-975 3275);
DISPLAY INVISIBLE (-975 3275);
FORCEADD OFFPAGE..1
R 2
(500 1475);
FORCEPROP 2 LAST $XR0 55 
J 0
(686 1475);
DISPLAY 0.638298 (686 1475);
PAINT MONO (686 1475);
FORCEPROP 1 LAST OFFPAGE TRUE
J 2
(175 1350);
DISPLAY 0.872340 (175 1350);
PAINT GREEN (175 1350);
DISPLAY INVISIBLE (175 1350);
FORCEPROP 2 LAST CDS_LIB mstr_standard
J 2
(500 1475);
PAINT ORANGE (500 1475);
DISPLAY INVISIBLE (500 1475);
FORCEPROP 1 LAST COMMENT_BODY TRUE
J 2
(375 1375);
DISPLAY 0.872340 (375 1375);
PAINT GREEN (375 1375);
DISPLAY INVISIBLE (375 1375);
FORCEPROP 2 LAST PATH I56
J 2
(300 1525);
DISPLAY 1.021277 (300 1525);
PAINT ORANGE (300 1525);
DISPLAY INVISIBLE (300 1525);
FORCEADD OFFPAGE..1
R 2
(500 1675);
FORCEPROP 2 LAST $XR0 55 
J 0
(686 1675);
DISPLAY 0.638298 (686 1675);
PAINT MONO (686 1675);
FORCEPROP 2 LAST CDS_LIB mstr_standard
J 2
(500 1675);
PAINT ORANGE (500 1675);
DISPLAY INVISIBLE (500 1675);
FORCEPROP 1 LAST OFFPAGE TRUE
J 2
(175 1550);
DISPLAY 0.872340 (175 1550);
PAINT GREEN (175 1550);
DISPLAY INVISIBLE (175 1550);
FORCEPROP 1 LAST COMMENT_BODY TRUE
J 2
(375 1575);
DISPLAY 0.872340 (375 1575);
PAINT GREEN (375 1575);
DISPLAY INVISIBLE (375 1575);
FORCEPROP 2 LAST PATH I57
J 2
(300 1725);
DISPLAY 1.021277 (300 1725);
PAINT ORANGE (300 1725);
DISPLAY INVISIBLE (300 1725);
FORCEADD RES..1
(-375 1675);
FORCEPROP 1 LAST LOCATION R3D24
J 0
(-600 1725);
DISPLAY 0.617021 (-600 1725);
PAINT AQUA (-600 1725);
FORCEPROP 1 LAST PART_NUMBER G21796-294
J 0
(-675 1625);
DISPLAY 0.617021 (-675 1625);
PAINT BLUE (-675 1625);
FORCEPROP 1 LAST VALUE 240
J 2
(-300 1725);
DISPLAY 0.617021 (-300 1725);
PAINT SKYBLUE (-300 1725);
FORCEPROP 1 LAST TOLERANCE 1.0%
J 0
(-275 1725);
DISPLAY 0.617021 (-275 1725);
PAINT SKYBLUE (-275 1725);
FORCEPROP 1 LAST PACK_TYPE 0402
J 0
(-350 1625);
DISPLAY 0.617021 (-350 1625);
PAINT SKYBLUE (-350 1625);
FORCEPROP 1 LAST MATERIAL CHIP
J 0
(-150 1625);
DISPLAY 0.617021 (-150 1625);
PAINT SKYBLUE (-150 1625);
FORCEPROP 1 LAST WATTAGE 1/16W
J 2
(0 1725);
DISPLAY 0.617021 (0 1725);
PAINT SKYBLUE (0 1725);
FORCEPROP 2 LAST CDS_LOCATION R3D24
J 0
(-600 1725);
DISPLAY 0.617021 (-600 1725);
PAINT AQUA (-600 1725);
DISPLAY INVISIBLE (-600 1725);
FORCEPROP 1 LASTPIN (-475 1675) $PN 1
J 0
(-463 1687);
DISPLAY 0.787234 (-463 1687);
PAINT ORANGE (-463 1687);
DISPLAY INVISIBLE (-463 1687);
FORCEPROP 2 LAST CDS_LIB mstr_discrete
J 0
(-375 1675);
PAINT ORANGE (-375 1675);
DISPLAY INVISIBLE (-375 1675);
FORCEPROP 2 LAST BOM_COST PROC
J 0
(-375 1675);
PAINT MONO (-375 1675);
DISPLAY INVISIBLE (-375 1675);
FORCEPROP 1 LASTPIN (-275 1675) $PN 2
J 0
(-313 1687);
DISPLAY 0.787234 (-313 1687);
PAINT ORANGE (-313 1687);
DISPLAY INVISIBLE (-313 1687);
FORCEPROP 2 LAST CDS_SEC 1
J 0
(-425 1875);
DISPLAY 1.021277 (-425 1875);
PAINT ORANGE (-425 1875);
DISPLAY INVISIBLE (-425 1875);
FORCEPROP 2 LAST $SEC 1
J 0
(-425 1875);
DISPLAY 0.680851 (-425 1875);
PAINT MONO (-425 1875);
DISPLAY INVISIBLE (-425 1875);
FORCEPROP 1 LAST PATH I59
J 0
(-425 1825);
DISPLAY 0.978723 (-425 1825);
PAINT WHITE (-425 1825);
DISPLAY INVISIBLE (-425 1825);
FORCEPROP 2 LAST ROOM PROC_SIDEBAND
J 0
(0 1775);
PAINT MONO (0 1775);
DISPLAY INVISIBLE (0 1775);
FORCEADD OFFPAGE..2
(-1300 4400);
FORCEPROP 2 LAST $XR0 21 
J 0
(-1111 4400);
DISPLAY 0.638298 (-1111 4400);
PAINT MONO (-1111 4400);
FORCEPROP 1 LAST COMMENT_BODY TRUE
J 0
(-1345 4305);
DISPLAY 1.170213 (-1345 4305);
PAINT GREEN (-1345 4305);
DISPLAY INVISIBLE (-1345 4305);
FORCEPROP 2 LAST CDS_LIB mstr_standard
J 0
(-1300 4400);
PAINT ORANGE (-1300 4400);
DISPLAY INVISIBLE (-1300 4400);
FORCEPROP 2 LAST PATH I6
J 0
(-1100 4450);
DISPLAY 1.021277 (-1100 4450);
PAINT ORANGE (-1100 4450);
DISPLAY INVISIBLE (-1100 4450);
FORCEPROP 1 LAST OFFPAGE TRUE
J 0
(-975 4275);
PAINT GREEN (-975 4275);
DISPLAY INVISIBLE (-975 4275);
FORCEADD RES..1
(-350 1475);
FORCEPROP 1 LAST LOCATION R3D17
J 0
(-600 1525);
DISPLAY 0.617021 (-600 1525);
PAINT AQUA (-600 1525);
FORCEPROP 1 LAST PART_NUMBER G21796-294
J 0
(-700 1425);
DISPLAY 0.617021 (-700 1425);
PAINT BLUE (-700 1425);
FORCEPROP 1 LAST PACK_TYPE 0402
J 0
(-325 1425);
DISPLAY 0.617021 (-325 1425);
PAINT SKYBLUE (-325 1425);
FORCEPROP 1 LAST VALUE 240
J 2
(-300 1525);
DISPLAY 0.617021 (-300 1525);
PAINT SKYBLUE (-300 1525);
FORCEPROP 1 LAST TOLERANCE 1.0%
J 0
(-250 1525);
DISPLAY 0.617021 (-250 1525);
PAINT SKYBLUE (-250 1525);
FORCEPROP 1 LAST MATERIAL EMPTY
J 0
(-125 1425);
DISPLAY 0.617021 (-125 1425);
PAINT RED (-125 1425);
FORCEPROP 1 LAST WATTAGE 1/16W
J 2
(25 1525);
DISPLAY 0.617021 (25 1525);
PAINT SKYBLUE (25 1525);
FORCEPROP 2 LAST CDS_LOCATION R3D17
J 0
(-600 1525);
DISPLAY 0.617021 (-600 1525);
PAINT AQUA (-600 1525);
DISPLAY INVISIBLE (-600 1525);
FORCEPROP 1 LASTPIN (-450 1475) $PN 1
J 0
(-438 1487);
DISPLAY 0.787234 (-438 1487);
PAINT ORANGE (-438 1487);
DISPLAY INVISIBLE (-438 1487);
FORCEPROP 2 LAST CDS_LIB mstr_discrete
J 0
(-350 1475);
PAINT ORANGE (-350 1475);
DISPLAY INVISIBLE (-350 1475);
FORCEPROP 2 LAST BOM_COST PROC
J 0
(-350 1475);
PAINT MONO (-350 1475);
DISPLAY INVISIBLE (-350 1475);
FORCEPROP 1 LASTPIN (-250 1475) $PN 2
J 0
(-288 1487);
DISPLAY 0.787234 (-288 1487);
PAINT ORANGE (-288 1487);
DISPLAY INVISIBLE (-288 1487);
FORCEPROP 2 LAST CDS_SEC 1
J 0
(-400 1675);
DISPLAY 1.021277 (-400 1675);
PAINT ORANGE (-400 1675);
DISPLAY INVISIBLE (-400 1675);
FORCEPROP 2 LAST $SEC 1
J 0
(-400 1675);
DISPLAY 0.680851 (-400 1675);
PAINT MONO (-400 1675);
DISPLAY INVISIBLE (-400 1675);
FORCEPROP 1 LAST PATH I60
J 0
(-400 1625);
DISPLAY 0.978723 (-400 1625);
PAINT WHITE (-400 1625);
DISPLAY INVISIBLE (-400 1625);
FORCEPROP 2 LAST ROOM PROC_SIDEBAND
J 0
(25 1575);
PAINT MONO (25 1575);
DISPLAY INVISIBLE (25 1575);
FORCEADD PVCCIO_CPU1..1
(-2950 2050);
FORCEPROP 3 LASTPIN (-2950 2000) SIG_NAME PVCCIO_CPU1\g
J 0
(-2940 2010);
DISPLAY 0.659574 (-2940 2010);
PAINT MONO (-2940 2010);
DISPLAY INVISIBLE (-2940 2010);
FORCEPROP 1 LAST VOLTAGE 1.1V
J 0
(-2995 2007);
DISPLAY 0.340426 (-2995 2007);
PAINT SKYBLUE (-2995 2007);
DISPLAY INVISIBLE (-2995 2007);
FORCEPROP 1 LAST BODY_TYPE PLUMBING
J 0
(-2995 2007);
DISPLAY 0.340426 (-2995 2007);
PAINT GREEN (-2995 2007);
DISPLAY INVISIBLE (-2995 2007);
FORCEPROP 2 LAST CDS_LIB mstr_symbols
J 0
(-2950 2050);
PAINT ORANGE (-2950 2050);
DISPLAY INVISIBLE (-2950 2050);
FORCEPROP 1 LAST PATH I62
J 0
(-2900 2075);
DISPLAY 0.872340 (-2900 2075);
PAINT AQUA (-2900 2075);
DISPLAY INVISIBLE (-2900 2075);
FORCEPROP 1 LAST HDL_POWER PVCCIO_CPU1
J 1
(-2950 2100);
DISPLAY 0.872340 (-2950 2100);
PAINT GREEN (-2950 2100);
DISPLAY INVISIBLE (-2950 2100);
FORCEADD PVCCIO_CPU1..1
(-725 1825);
FORCEPROP 3 LASTPIN (-725 1775) SIG_NAME PVCCIO_CPU1\g
J 0
(-715 1785);
DISPLAY 0.659574 (-715 1785);
PAINT MONO (-715 1785);
DISPLAY INVISIBLE (-715 1785);
FORCEPROP 1 LAST VOLTAGE 1.1V
J 0
(-770 1782);
DISPLAY 0.340426 (-770 1782);
PAINT SKYBLUE (-770 1782);
DISPLAY INVISIBLE (-770 1782);
FORCEPROP 1 LAST BODY_TYPE PLUMBING
J 0
(-770 1782);
DISPLAY 0.340426 (-770 1782);
PAINT GREEN (-770 1782);
DISPLAY INVISIBLE (-770 1782);
FORCEPROP 1 LAST HDL_POWER PVCCIO_CPU1
J 1
(-725 1875);
DISPLAY 0.872340 (-725 1875);
PAINT GREEN (-725 1875);
DISPLAY INVISIBLE (-725 1875);
FORCEPROP 1 LAST PATH I63
J 0
(-675 1850);
DISPLAY 0.872340 (-675 1850);
PAINT AQUA (-675 1850);
DISPLAY INVISIBLE (-675 1850);
FORCEPROP 2 LAST CDS_LIB mstr_symbols
J 0
(-725 1825);
PAINT ORANGE (-725 1825);
DISPLAY INVISIBLE (-725 1825);
FORCEADD OFFPAGE..2
(-1325 1025);
FORCEPROP 2 LAST $XR0 55 
J 0
(-1136 1025);
DISPLAY 0.638298 (-1136 1025);
PAINT MONO (-1136 1025);
FORCEPROP 1 LAST COMMENT_BODY TRUE
J 0
(-1370 930);
DISPLAY 1.170213 (-1370 930);
PAINT GREEN (-1370 930);
DISPLAY INVISIBLE (-1370 930);
FORCEPROP 2 LAST CDS_LIB mstr_standard
J 0
(-1325 1025);
PAINT ORANGE (-1325 1025);
DISPLAY INVISIBLE (-1325 1025);
FORCEPROP 2 LAST PATH I64
J 0
(-1150 1100);
DISPLAY 1.021277 (-1150 1100);
PAINT ORANGE (-1150 1100);
DISPLAY INVISIBLE (-1150 1100);
FORCEPROP 1 LAST OFFPAGE TRUE
J 0
(-1000 900);
PAINT GREEN (-1000 900);
DISPLAY INVISIBLE (-1000 900);
FORCEADD RES..1
(-2500 1025);
FORCEPROP 1 LAST PART_NUMBER G21796-294
J 0
(-2850 975);
DISPLAY 0.617021 (-2850 975);
PAINT BLUE (-2850 975);
FORCEPROP 1 LAST PACK_TYPE 0402
J 0
(-2475 975);
DISPLAY 0.617021 (-2475 975);
PAINT SKYBLUE (-2475 975);
FORCEPROP 1 LAST MATERIAL EMPTY
J 0
(-2275 975);
DISPLAY 0.617021 (-2275 975);
PAINT RED (-2275 975);
FORCEPROP 1 LAST LOCATION R3D25
J 0
(-2750 1050);
DISPLAY 0.617021 (-2750 1050);
PAINT AQUA (-2750 1050);
FORCEPROP 1 LASTPIN (-2600 1025) $PN 1
J 0
(-2588 1037);
DISPLAY 0.617021 (-2588 1037);
PAINT ORANGE (-2588 1037);
FORCEPROP 1 LAST VALUE 240
J 2
(-2425 1075);
DISPLAY 0.617021 (-2425 1075);
PAINT SKYBLUE (-2425 1075);
FORCEPROP 1 LASTPIN (-2400 1025) $PN 2
J 0
(-2438 1037);
DISPLAY 0.617021 (-2438 1037);
PAINT ORANGE (-2438 1037);
FORCEPROP 1 LAST TOLERANCE 1.0%
J 0
(-2400 1075);
DISPLAY 0.617021 (-2400 1075);
PAINT SKYBLUE (-2400 1075);
FORCEPROP 1 LAST WATTAGE 1/16W
J 2
(-2150 1075);
DISPLAY 0.617021 (-2150 1075);
PAINT SKYBLUE (-2150 1075);
FORCEPROP 2 LAST CDS_LOCATION R3D25
J 0
(-2750 1050);
DISPLAY 0.617021 (-2750 1050);
PAINT AQUA (-2750 1050);
DISPLAY INVISIBLE (-2750 1050);
FORCEPROP 2 LAST CDS_LIB mstr_discrete
J 0
(-2500 1025);
PAINT ORANGE (-2500 1025);
DISPLAY INVISIBLE (-2500 1025);
FORCEPROP 2 LAST BOM_COST PROC
J 0
(-2500 1025);
PAINT MONO (-2500 1025);
DISPLAY INVISIBLE (-2500 1025);
FORCEPROP 1 LAST PATH I66
J 0
(-2550 1175);
DISPLAY 0.978723 (-2550 1175);
PAINT WHITE (-2550 1175);
DISPLAY INVISIBLE (-2550 1175);
FORCEPROP 2 LAST SEC 1
J 0
(-2550 1225);
DISPLAY 0.680851 (-2550 1225);
PAINT MONO (-2550 1225);
DISPLAY INVISIBLE (-2550 1225);
FORCEPROP 2 LAST SEC_TYPE 0402
J 0
(-2550 1225);
DISPLAY 1.021277 (-2550 1225);
PAINT ORANGE (-2550 1225);
DISPLAY INVISIBLE (-2550 1225);
FORCEPROP 2 LAST ROOM PROC_SIDEBAND
J 0
(-2150 1125);
PAINT MONO (-2150 1125);
DISPLAY INVISIBLE (-2150 1125);
FORCEADD RES..1
(-425 3000);
FORCEPROP 1 LAST LOCATION R4P6
J 0
(-700 3025);
DISPLAY 0.617021 (-700 3025);
PAINT AQUA (-700 3025);
FORCEPROP 1 LAST PART_NUMBER G21796-294
J 0
(-775 2950);
DISPLAY 0.617021 (-775 2950);
PAINT BLUE (-775 2950);
FORCEPROP 1 LASTPIN (-525 3000) $PN 1
J 0
(-513 3012);
DISPLAY 0.617021 (-513 3012);
PAINT ORANGE (-513 3012);
FORCEPROP 1 LASTPIN (-325 3000) $PN 2
J 0
(-363 3012);
DISPLAY 0.617021 (-363 3012);
PAINT ORANGE (-363 3012);
FORCEPROP 1 LAST PACK_TYPE 0402
J 0
(-300 2950);
DISPLAY 0.617021 (-300 2950);
PAINT SKYBLUE (-300 2950);
FORCEPROP 1 LAST MATERIAL EMPTY
J 0
(-175 2950);
DISPLAY 0.617021 (-175 2950);
PAINT RED (-175 2950);
FORCEPROP 1 LAST VALUE 240
J 2
(-350 3050);
DISPLAY 0.617021 (-350 3050);
PAINT SKYBLUE (-350 3050);
FORCEPROP 1 LAST TOLERANCE 1.0%
J 0
(-325 3050);
DISPLAY 0.617021 (-325 3050);
PAINT SKYBLUE (-325 3050);
FORCEPROP 1 LAST WATTAGE 1/16W
J 2
(-50 3050);
DISPLAY 0.617021 (-50 3050);
PAINT SKYBLUE (-50 3050);
FORCEPROP 2 LAST CDS_LOCATION R4P6
J 0
(-700 3025);
DISPLAY 0.617021 (-700 3025);
PAINT AQUA (-700 3025);
DISPLAY INVISIBLE (-700 3025);
FORCEPROP 2 LAST BOM_COST PROC
J 0
(-425 3000);
PAINT MONO (-425 3000);
DISPLAY INVISIBLE (-425 3000);
FORCEPROP 2 LAST CDS_LIB mstr_discrete
J 0
(-425 3000);
PAINT ORANGE (-425 3000);
DISPLAY INVISIBLE (-425 3000);
FORCEPROP 1 LAST PATH I68
J 0
(-475 3150);
DISPLAY 0.978723 (-475 3150);
PAINT WHITE (-475 3150);
DISPLAY INVISIBLE (-475 3150);
FORCEPROP 2 LAST SEC_TYPE 0402
J 0
(-475 3200);
DISPLAY 1.021277 (-475 3200);
PAINT ORANGE (-475 3200);
DISPLAY INVISIBLE (-475 3200);
FORCEPROP 2 LAST SEC 1
J 0
(-475 3200);
DISPLAY 0.680851 (-475 3200);
PAINT MONO (-475 3200);
DISPLAY INVISIBLE (-475 3200);
FORCEPROP 0 LAST ROOM PROC_SIDEBAND
J 0
(-50 3150);
DISPLAY 1.021277 (-50 3150);
PAINT ORANGE (-50 3150);
DISPLAY INVISIBLE (-50 3150);
FORCEADD OFFPAGE..2
(475 3000);
FORCEPROP 2 LAST $XR0 22 
J 0
(664 3000);
DISPLAY 0.638298 (664 3000);
PAINT MONO (664 3000);
FORCEPROP 1 LAST COMMENT_BODY TRUE
J 0
(430 2905);
DISPLAY 1.170213 (430 2905);
PAINT GREEN (430 2905);
DISPLAY INVISIBLE (430 2905);
FORCEPROP 2 LAST CDS_LIB mstr_standard
J 0
(475 3000);
PAINT ORANGE (475 3000);
DISPLAY INVISIBLE (475 3000);
FORCEPROP 1 LAST OFFPAGE TRUE
J 0
(800 2875);
PAINT GREEN (800 2875);
DISPLAY INVISIBLE (800 2875);
FORCEPROP 2 LAST PATH I69
J 0
(650 3075);
DISPLAY 1.021277 (650 3075);
PAINT ORANGE (650 3075);
DISPLAY INVISIBLE (650 3075);
FORCEADD OFFPAGE..2
(-1300 4200);
FORCEPROP 2 LAST $XR0 156 
J 0
(-1111 4200);
DISPLAY 0.638298 (-1111 4200);
PAINT MONO (-1111 4200);
FORCEPROP 2 LAST $XR1 21 
J 0
(-991 4200);
DISPLAY 0.638298 (-991 4200);
PAINT MONO (-991 4200);
FORCEPROP 1 LAST OFFPAGE TRUE
J 0
(-975 4075);
PAINT GREEN (-975 4075);
DISPLAY INVISIBLE (-975 4075);
FORCEPROP 2 LAST CDS_LIB mstr_standard
J 0
(-1300 4200);
PAINT ORANGE (-1300 4200);
DISPLAY INVISIBLE (-1300 4200);
FORCEPROP 1 LAST COMMENT_BODY TRUE
J 0
(-1345 4105);
DISPLAY 1.170213 (-1345 4105);
PAINT GREEN (-1345 4105);
DISPLAY INVISIBLE (-1345 4105);
FORCEPROP 2 LAST PATH I7
J 0
(-1100 4250);
DISPLAY 1.021277 (-1100 4250);
PAINT ORANGE (-1100 4250);
DISPLAY INVISIBLE (-1100 4250);
FORCEADD RES..1
(-275 850);
FORCEPROP 1 LAST LOCATION R7P14
J 0
(-575 875);
DISPLAY 0.617021 (-575 875);
PAINT AQUA (-575 875);
FORCEPROP 1 LAST PART_NUMBER G21796-294
J 0
(-625 800);
DISPLAY 0.617021 (-625 800);
PAINT BLUE (-625 800);
FORCEPROP 1 LASTPIN (-375 850) $PN 1
J 0
(-363 862);
DISPLAY 0.617021 (-363 862);
PAINT ORANGE (-363 862);
FORCEPROP 1 LAST VALUE 240
J 2
(-200 900);
DISPLAY 0.617021 (-200 900);
PAINT SKYBLUE (-200 900);
FORCEPROP 1 LAST TOLERANCE 1.0%
J 0
(-175 900);
DISPLAY 0.617021 (-175 900);
PAINT SKYBLUE (-175 900);
FORCEPROP 1 LAST PACK_TYPE 0402
J 0
(-250 800);
DISPLAY 0.617021 (-250 800);
PAINT SKYBLUE (-250 800);
FORCEPROP 1 LASTPIN (-175 850) $PN 2
J 0
(-213 862);
DISPLAY 0.617021 (-213 862);
PAINT ORANGE (-213 862);
FORCEPROP 1 LAST WATTAGE 1/16W
J 2
(100 900);
DISPLAY 0.617021 (100 900);
PAINT SKYBLUE (100 900);
FORCEPROP 2 LAST CDS_LOCATION R7P14
J 0
(-575 875);
DISPLAY 0.617021 (-575 875);
PAINT AQUA (-575 875);
DISPLAY INVISIBLE (-575 875);
FORCEPROP 2 LAST CDS_LIB mstr_discrete
J 0
(-275 850);
PAINT ORANGE (-275 850);
DISPLAY INVISIBLE (-275 850);
FORCEPROP 2 LAST BOM_COST PROC
J 0
(-275 850);
PAINT MONO (-275 850);
DISPLAY INVISIBLE (-275 850);
FORCEPROP 1 LAST MATERIAL CHIP
J 0
(-50 800);
PAINT SKYBLUE (-50 800);
DISPLAY INVISIBLE (-50 800);
FORCEPROP 1 LAST PATH I70
J 0
(-325 1000);
DISPLAY 0.978723 (-325 1000);
PAINT WHITE (-325 1000);
DISPLAY INVISIBLE (-325 1000);
FORCEPROP 2 LAST SEC_TYPE 0402
J 0
(-325 1050);
DISPLAY 1.021277 (-325 1050);
PAINT ORANGE (-325 1050);
DISPLAY INVISIBLE (-325 1050);
FORCEPROP 2 LAST SEC 1
J 0
(-325 1050);
DISPLAY 0.680851 (-325 1050);
PAINT MONO (-325 1050);
DISPLAY INVISIBLE (-325 1050);
FORCEPROP 0 LAST ROOM PROC_SIDEBAND
J 0
(100 1000);
DISPLAY 1.021277 (100 1000);
PAINT ORANGE (100 1000);
DISPLAY INVISIBLE (100 1000);
FORCEADD OFFPAGE..2
(675 850);
FORCEPROP 2 LAST $XR0 56 
J 0
(864 850);
DISPLAY 0.638298 (864 850);
PAINT MONO (864 850);
FORCEPROP 1 LAST COMMENT_BODY TRUE
J 0
(630 755);
DISPLAY 1.170213 (630 755);
PAINT GREEN (630 755);
DISPLAY INVISIBLE (630 755);
FORCEPROP 2 LAST CDS_LIB mstr_standard
J 0
(675 850);
PAINT ORANGE (675 850);
DISPLAY INVISIBLE (675 850);
FORCEPROP 1 LAST OFFPAGE TRUE
J 0
(1000 725);
PAINT GREEN (1000 725);
DISPLAY INVISIBLE (1000 725);
FORCEPROP 2 LAST PATH I71
J 0
(850 925);
DISPLAY 1.021277 (850 925);
PAINT ORANGE (850 925);
DISPLAY INVISIBLE (850 925);
FORCEADD RES..1
(-425 2800);
FORCEPROP 1 LAST LOCATION R4P7
J 0
(-700 2825);
DISPLAY 0.617021 (-700 2825);
PAINT AQUA (-700 2825);
FORCEPROP 1 LAST PART_NUMBER G21796-294
J 0
(-750 2750);
DISPLAY 0.617021 (-750 2750);
PAINT BLUE (-750 2750);
FORCEPROP 1 LASTPIN (-525 2800) $PN 1
J 0
(-513 2812);
DISPLAY 0.617021 (-513 2812);
PAINT ORANGE (-513 2812);
FORCEPROP 1 LASTPIN (-325 2800) $PN 2
J 0
(-363 2812);
DISPLAY 0.617021 (-363 2812);
PAINT ORANGE (-363 2812);
FORCEPROP 1 LAST VALUE 240
J 2
(-225 2850);
DISPLAY 0.617021 (-225 2850);
PAINT SKYBLUE (-225 2850);
FORCEPROP 1 LAST PACK_TYPE 0402
J 0
(-350 2725);
DISPLAY 0.617021 (-350 2725);
PAINT SKYBLUE (-350 2725);
FORCEPROP 1 LAST TOLERANCE 1.0%
J 0
(-200 2850);
DISPLAY 0.617021 (-200 2850);
PAINT SKYBLUE (-200 2850);
FORCEPROP 1 LAST MATERIAL EMPTY
J 0
(-225 2725);
DISPLAY 0.617021 (-225 2725);
PAINT RED (-225 2725);
FORCEPROP 1 LAST WATTAGE 1/16W
J 2
(50 2850);
DISPLAY 0.617021 (50 2850);
PAINT SKYBLUE (50 2850);
FORCEPROP 2 LAST CDS_LOCATION R4P7
J 0
(-700 2825);
DISPLAY 0.617021 (-700 2825);
PAINT AQUA (-700 2825);
DISPLAY INVISIBLE (-700 2825);
FORCEPROP 2 LAST CDS_LIB mstr_discrete
J 0
(-425 2800);
PAINT ORANGE (-425 2800);
DISPLAY INVISIBLE (-425 2800);
FORCEPROP 2 LAST BOM_COST PROC
J 0
(-425 2800);
PAINT MONO (-425 2800);
DISPLAY INVISIBLE (-425 2800);
FORCEPROP 2 LAST SEC 1
J 0
(-475 3000);
DISPLAY 0.680851 (-475 3000);
PAINT MONO (-475 3000);
DISPLAY INVISIBLE (-475 3000);
FORCEPROP 2 LAST SEC_TYPE 0402
J 0
(-475 3000);
DISPLAY 1.021277 (-475 3000);
PAINT ORANGE (-475 3000);
DISPLAY INVISIBLE (-475 3000);
FORCEPROP 1 LAST PATH I72
J 0
(-475 2950);
DISPLAY 0.978723 (-475 2950);
PAINT WHITE (-475 2950);
DISPLAY INVISIBLE (-475 2950);
FORCEPROP 0 LAST ROOM PROC_SIDEBAND
J 0
(-50 2950);
DISPLAY 1.021277 (-50 2950);
PAINT ORANGE (-50 2950);
DISPLAY INVISIBLE (-50 2950);
FORCEADD OFFPAGE..2
(475 2800);
FORCEPROP 2 LAST $XR0 21 
J 0
(664 2800);
DISPLAY 0.638298 (664 2800);
PAINT MONO (664 2800);
FORCEPROP 1 LAST COMMENT_BODY TRUE
J 0
(430 2705);
DISPLAY 1.170213 (430 2705);
PAINT GREEN (430 2705);
DISPLAY INVISIBLE (430 2705);
FORCEPROP 2 LAST CDS_LIB mstr_standard
J 0
(475 2800);
PAINT ORANGE (475 2800);
DISPLAY INVISIBLE (475 2800);
FORCEPROP 2 LAST PATH I73
J 0
(650 2875);
DISPLAY 1.021277 (650 2875);
PAINT ORANGE (650 2875);
DISPLAY INVISIBLE (650 2875);
FORCEPROP 1 LAST OFFPAGE TRUE
J 0
(800 2675);
PAINT GREEN (800 2675);
DISPLAY INVISIBLE (800 2675);
FORCEADD RES..1
(-275 650);
FORCEPROP 1 LAST PART_NUMBER G21796-294
J 0
(-675 600);
DISPLAY 0.617021 (-675 600);
PAINT BLUE (-675 600);
FORCEPROP 1 LAST LOCATION R7P15
J 0
(-575 675);
DISPLAY 0.617021 (-575 675);
PAINT AQUA (-575 675);
FORCEPROP 1 LASTPIN (-375 650) $PN 1
J 0
(-363 662);
DISPLAY 0.617021 (-363 662);
PAINT ORANGE (-363 662);
FORCEPROP 1 LASTPIN (-175 650) $PN 2
J 0
(-213 662);
DISPLAY 0.617021 (-213 662);
PAINT ORANGE (-213 662);
FORCEPROP 1 LAST VALUE 240
J 2
(-50 700);
DISPLAY 0.617021 (-50 700);
PAINT SKYBLUE (-50 700);
FORCEPROP 1 LAST TOLERANCE 1.0%
J 0
(0 700);
DISPLAY 0.617021 (0 700);
PAINT SKYBLUE (0 700);
FORCEPROP 1 LAST PACK_TYPE 0402
J 0
(-100 575);
DISPLAY 0.617021 (-100 575);
PAINT SKYBLUE (-100 575);
FORCEPROP 1 LAST WATTAGE 1/16W
J 2
(300 700);
DISPLAY 0.617021 (300 700);
PAINT SKYBLUE (300 700);
FORCEPROP 1 LAST MATERIAL EMPTY
J 0
(25 575);
DISPLAY 0.617021 (25 575);
PAINT RED (25 575);
FORCEPROP 2 LAST CDS_LOCATION R7P15
J 0
(-575 675);
DISPLAY 0.617021 (-575 675);
PAINT AQUA (-575 675);
DISPLAY INVISIBLE (-575 675);
FORCEPROP 2 LAST CDS_LIB mstr_discrete
J 0
(-275 650);
PAINT ORANGE (-275 650);
DISPLAY INVISIBLE (-275 650);
FORCEPROP 2 LAST BOM_COST PROC
J 0
(-275 650);
PAINT MONO (-275 650);
DISPLAY INVISIBLE (-275 650);
FORCEPROP 2 LAST SEC 1
J 0
(-325 850);
DISPLAY 0.680851 (-325 850);
PAINT MONO (-325 850);
DISPLAY INVISIBLE (-325 850);
FORCEPROP 2 LAST SEC_TYPE 0402
J 0
(-325 850);
DISPLAY 1.021277 (-325 850);
PAINT ORANGE (-325 850);
DISPLAY INVISIBLE (-325 850);
FORCEPROP 1 LAST PATH I74
J 0
(-325 800);
DISPLAY 0.978723 (-325 800);
PAINT WHITE (-325 800);
DISPLAY INVISIBLE (-325 800);
FORCEPROP 0 LAST ROOM PROC_SIDEBAND
J 0
(100 800);
DISPLAY 1.021277 (100 800);
PAINT ORANGE (100 800);
DISPLAY INVISIBLE (100 800);
FORCEADD OFFPAGE..2
(675 650);
FORCEPROP 2 LAST $XR0 55 
J 0
(864 650);
DISPLAY 0.638298 (864 650);
PAINT MONO (864 650);
FORCEPROP 1 LAST COMMENT_BODY TRUE
J 0
(630 555);
DISPLAY 1.170213 (630 555);
PAINT GREEN (630 555);
DISPLAY INVISIBLE (630 555);
FORCEPROP 2 LAST CDS_LIB mstr_standard
J 0
(675 650);
PAINT ORANGE (675 650);
DISPLAY INVISIBLE (675 650);
FORCEPROP 2 LAST PATH I75
J 0
(850 725);
DISPLAY 1.021277 (850 725);
PAINT ORANGE (850 725);
DISPLAY INVISIBLE (850 725);
FORCEPROP 1 LAST OFFPAGE TRUE
J 0
(1000 525);
PAINT GREEN (1000 525);
DISPLAY INVISIBLE (1000 525);
FORCEADD RES..1
(-2475 800);
FORCEPROP 1 LAST PART_NUMBER G21796-294
J 0
(-2950 750);
DISPLAY 0.617021 (-2950 750);
PAINT BLUE (-2950 750);
FORCEPROP 1 LAST LOCATION R7P22
J 0
(-2750 825);
DISPLAY 0.617021 (-2750 825);
PAINT AQUA (-2750 825);
FORCEPROP 1 LAST PACK_TYPE 0402
J 0
(-2625 650);
DISPLAY 0.617021 (-2625 650);
PAINT SKYBLUE (-2625 650);
FORCEPROP 1 LASTPIN (-2575 800) $PN 1
J 0
(-2563 812);
DISPLAY 0.617021 (-2563 812);
PAINT ORANGE (-2563 812);
FORCEPROP 1 LAST MATERIAL EMPTY
J 0
(-2475 650);
DISPLAY 0.617021 (-2475 650);
PAINT RED (-2475 650);
FORCEPROP 1 LAST VALUE 240
J 2
(-2425 850);
DISPLAY 0.617021 (-2425 850);
PAINT SKYBLUE (-2425 850);
FORCEPROP 1 LASTPIN (-2375 800) $PN 2
J 0
(-2413 812);
DISPLAY 0.617021 (-2413 812);
PAINT ORANGE (-2413 812);
FORCEPROP 1 LAST TOLERANCE 1.0%
J 0
(-2325 850);
DISPLAY 0.617021 (-2325 850);
PAINT SKYBLUE (-2325 850);
FORCEPROP 1 LAST WATTAGE 1/16W
J 2
(-2075 850);
DISPLAY 0.617021 (-2075 850);
PAINT SKYBLUE (-2075 850);
FORCEPROP 2 LAST CDS_LOCATION R7P22
J 0
(-2750 825);
DISPLAY 0.617021 (-2750 825);
PAINT AQUA (-2750 825);
DISPLAY INVISIBLE (-2750 825);
FORCEPROP 2 LAST CDS_LIB mstr_discrete
J 0
(-2475 800);
PAINT ORANGE (-2475 800);
DISPLAY INVISIBLE (-2475 800);
FORCEPROP 0 LAST BOM_COST PROC
J 0
(-2525 950);
DISPLAY 1.021277 (-2525 950);
PAINT ORANGE (-2525 950);
DISPLAY INVISIBLE (-2525 950);
FORCEPROP 1 LAST PATH I76
J 0
(-2525 950);
DISPLAY 0.978723 (-2525 950);
PAINT WHITE (-2525 950);
DISPLAY INVISIBLE (-2525 950);
FORCEPROP 0 LAST ROOM PROC_SIDEBAND
J 0
(-2525 950);
DISPLAY 1.021277 (-2525 950);
PAINT ORANGE (-2525 950);
DISPLAY INVISIBLE (-2525 950);
FORCEPROP 2 LAST SEC_TYPE 0402
J 0
(-2525 1000);
DISPLAY 1.021277 (-2525 1000);
PAINT ORANGE (-2525 1000);
DISPLAY INVISIBLE (-2525 1000);
FORCEPROP 2 LAST SEC 1
J 0
(-2525 1000);
DISPLAY 0.680851 (-2525 1000);
PAINT MONO (-2525 1000);
DISPLAY INVISIBLE (-2525 1000);
FORCEADD OFFPAGE..2
(-1325 800);
FORCEPROP 2 LAST $XR0 55 
J 0
(-1136 800);
DISPLAY 0.638298 (-1136 800);
PAINT MONO (-1136 800);
FORCEPROP 1 LAST COMMENT_BODY TRUE
J 0
(-1370 705);
DISPLAY 1.170213 (-1370 705);
PAINT GREEN (-1370 705);
DISPLAY INVISIBLE (-1370 705);
FORCEPROP 2 LAST CDS_LIB mstr_standard
J 0
(-1325 800);
PAINT ORANGE (-1325 800);
DISPLAY INVISIBLE (-1325 800);
FORCEPROP 2 LAST PATH I77
J 0
(-1150 875);
DISPLAY 1.021277 (-1150 875);
PAINT ORANGE (-1150 875);
DISPLAY INVISIBLE (-1150 875);
FORCEPROP 1 LAST OFFPAGE TRUE
J 0
(-1000 675);
PAINT GREEN (-1000 675);
DISPLAY INVISIBLE (-1000 675);
FORCEADD GND..1
(-1225 2725);
FORCEPROP 3 LASTPIN (-1225 2775) SIG_NAME GND\g
J 0
(-1215 2785);
DISPLAY 0.659574 (-1215 2785);
PAINT MONO (-1215 2785);
DISPLAY INVISIBLE (-1215 2785);
FORCEPROP 1 LAST PATH I78
J 0
(-1150 2725);
DISPLAY 0.872340 (-1150 2725);
PAINT AQUA (-1150 2725);
DISPLAY INVISIBLE (-1150 2725);
FORCEPROP 1 LAST SIZE 1B
J 0
(-1150 2675);
DISPLAY 1.170213 (-1150 2675);
PAINT GREEN (-1150 2675);
DISPLAY INVISIBLE (-1150 2675);
FORCEPROP 2 LAST CDS_LIB mstr_symbols
J 0
(-1225 2725);
PAINT ORANGE (-1225 2725);
DISPLAY INVISIBLE (-1225 2725);
FORCEPROP 1 LAST VOLTAGE 0.0V
J 0
(-1270 2682);
DISPLAY 0.340426 (-1270 2682);
PAINT SKYBLUE (-1270 2682);
DISPLAY INVISIBLE (-1270 2682);
FORCEPROP 1 LAST BODY_TYPE PLUMBING
J 0
(-1270 2682);
DISPLAY 0.340426 (-1270 2682);
PAINT GREEN (-1270 2682);
DISPLAY INVISIBLE (-1270 2682);
FORCEPROP 1 LAST HDL_POWER GND
J 0
(-1225 2875);
DISPLAY 0.702128 (-1225 2875);
PAINT GREEN (-1225 2875);
DISPLAY INVISIBLE (-1225 2875);
FORCEADD RES..1
(-1575 3200);
FORCEPROP 1 LAST PACK_TYPE 0402
J 0
(-2150 3150);
DISPLAY 0.617021 (-2150 3150);
PAINT SKYBLUE (-2150 3150);
FORCEPROP 1 LAST MATERIAL CHIP
J 0
(-2000 3150);
DISPLAY 0.617021 (-2000 3150);
PAINT SKYBLUE (-2000 3150);
FORCEPROP 1 LAST WATTAGE 1/16W
J 2
(-1750 3150);
DISPLAY 0.617021 (-1750 3150);
PAINT SKYBLUE (-1750 3150);
FORCEPROP 1 LAST VALUE 49.9
J 2
(-1625 3150);
DISPLAY 0.617021 (-1625 3150);
PAINT SKYBLUE (-1625 3150);
FORCEPROP 1 LASTPIN (-1675 3200) $PN 1
J 0
(-1663 3212);
DISPLAY 0.617021 (-1663 3212);
PAINT ORANGE (-1663 3212);
FORCEPROP 1 LAST LOCATION R5P2
J 0
(-1625 3250);
DISPLAY 0.617021 (-1625 3250);
PAINT AQUA (-1625 3250);
FORCEPROP 1 LAST TOLERANCE 1%
J 0
(-1550 3150);
DISPLAY 0.617021 (-1550 3150);
PAINT SKYBLUE (-1550 3150);
FORCEPROP 1 LASTPIN (-1475 3200) $PN 2
J 0
(-1513 3212);
DISPLAY 0.617021 (-1513 3212);
PAINT ORANGE (-1513 3212);
FORCEPROP 1 LAST PART_NUMBER G21796-047
J 0
(-1450 3150);
DISPLAY 0.617021 (-1450 3150);
PAINT BLUE (-1450 3150);
FORCEPROP 2 LAST CDS_LIB mstr_discrete
J 0
(-1575 3200);
PAINT ORANGE (-1575 3200);
DISPLAY INVISIBLE (-1575 3200);
FORCEPROP 2 LAST CDS_LOCATION R5P2
J 0
(-1625 3250);
DISPLAY 0.617021 (-1625 3250);
PAINT AQUA (-1625 3250);
DISPLAY INVISIBLE (-1625 3250);
FORCEPROP 2 LAST SEC_TYPE 0402
J 0
(-1625 3400);
DISPLAY 1.021277 (-1625 3400);
PAINT ORANGE (-1625 3400);
DISPLAY INVISIBLE (-1625 3400);
FORCEPROP 2 LAST SEC 1
J 0
(-1625 3400);
DISPLAY 0.680851 (-1625 3400);
PAINT MONO (-1625 3400);
DISPLAY INVISIBLE (-1625 3400);
FORCEPROP 1 LAST PATH I79
J 0
(-1625 3350);
DISPLAY 0.978723 (-1625 3350);
PAINT WHITE (-1625 3350);
DISPLAY INVISIBLE (-1625 3350);
FORCEPROP 0 LAST ROOM CPU0
J 0
(-1625 3350);
DISPLAY 1.021277 (-1625 3350);
PAINT ORANGE (-1625 3350);
DISPLAY INVISIBLE (-1625 3350);
FORCEADD OFFPAGE..2
(-1300 4000);
FORCEPROP 2 LAST $XR0 21 
J 0
(-1111 4000);
DISPLAY 0.638298 (-1111 4000);
PAINT MONO (-1111 4000);
FORCEPROP 1 LAST COMMENT_BODY TRUE
J 0
(-1345 3905);
DISPLAY 1.170213 (-1345 3905);
PAINT GREEN (-1345 3905);
DISPLAY INVISIBLE (-1345 3905);
FORCEPROP 2 LAST CDS_LIB mstr_standard
J 0
(-1300 4000);
PAINT ORANGE (-1300 4000);
DISPLAY INVISIBLE (-1300 4000);
FORCEPROP 2 LAST PATH I8
J 0
(-1100 4050);
DISPLAY 1.021277 (-1100 4050);
PAINT ORANGE (-1100 4050);
DISPLAY INVISIBLE (-1100 4050);
FORCEPROP 1 LAST OFFPAGE TRUE
J 0
(-975 3875);
PAINT GREEN (-975 3875);
DISPLAY INVISIBLE (-975 3875);
FORCEADD RES..1
(-1575 3075);
FORCEPROP 1 LAST PACK_TYPE 0402
J 0
(-2150 3025);
DISPLAY 0.617021 (-2150 3025);
PAINT SKYBLUE (-2150 3025);
FORCEPROP 1 LAST MATERIAL CHIP
J 0
(-2000 3025);
DISPLAY 0.617021 (-2000 3025);
PAINT SKYBLUE (-2000 3025);
FORCEPROP 1 LAST WATTAGE 1/16W
J 2
(-1750 3025);
DISPLAY 0.617021 (-1750 3025);
PAINT SKYBLUE (-1750 3025);
FORCEPROP 1 LAST VALUE 49.9
J 2
(-1625 3025);
DISPLAY 0.617021 (-1625 3025);
PAINT SKYBLUE (-1625 3025);
FORCEPROP 1 LAST TOLERANCE 1%
J 0
(-1550 3025);
DISPLAY 0.617021 (-1550 3025);
PAINT SKYBLUE (-1550 3025);
FORCEPROP 1 LAST PART_NUMBER G21796-047
J 0
(-1450 3025);
DISPLAY 0.617021 (-1450 3025);
PAINT BLUE (-1450 3025);
FORCEPROP 1 LASTPIN (-1675 3075) $PN 1
J 0
(-1663 3087);
DISPLAY 0.617021 (-1663 3087);
PAINT ORANGE (-1663 3087);
FORCEPROP 1 LAST LOCATION R5P3
J 0
(-1625 3125);
DISPLAY 0.617021 (-1625 3125);
PAINT AQUA (-1625 3125);
FORCEPROP 1 LASTPIN (-1475 3075) $PN 2
J 0
(-1513 3087);
DISPLAY 0.617021 (-1513 3087);
PAINT ORANGE (-1513 3087);
FORCEPROP 2 LAST CDS_LIB mstr_discrete
J 0
(-1575 3075);
PAINT ORANGE (-1575 3075);
DISPLAY INVISIBLE (-1575 3075);
FORCEPROP 2 LAST CDS_LOCATION R5P3
J 0
(-1625 3125);
DISPLAY 0.617021 (-1625 3125);
PAINT AQUA (-1625 3125);
DISPLAY INVISIBLE (-1625 3125);
FORCEPROP 2 LAST SEC 1
J 0
(-1625 3275);
DISPLAY 0.680851 (-1625 3275);
PAINT MONO (-1625 3275);
DISPLAY INVISIBLE (-1625 3275);
FORCEPROP 2 LAST SEC_TYPE 0402
J 0
(-1625 3275);
DISPLAY 1.021277 (-1625 3275);
PAINT ORANGE (-1625 3275);
DISPLAY INVISIBLE (-1625 3275);
FORCEPROP 1 LAST PATH I80
J 0
(-1625 3225);
DISPLAY 0.978723 (-1625 3225);
PAINT WHITE (-1625 3225);
DISPLAY INVISIBLE (-1625 3225);
FORCEPROP 0 LAST ROOM CPU0
J 0
(-1625 3225);
DISPLAY 1.021277 (-1625 3225);
PAINT ORANGE (-1625 3225);
DISPLAY INVISIBLE (-1625 3225);
FORCEADD RES..1
(-1575 2925);
FORCEPROP 1 LAST PACK_TYPE 0402
J 0
(-2150 2875);
DISPLAY 0.617021 (-2150 2875);
PAINT SKYBLUE (-2150 2875);
FORCEPROP 1 LAST MATERIAL CHIP
J 0
(-2000 2875);
DISPLAY 0.617021 (-2000 2875);
PAINT SKYBLUE (-2000 2875);
FORCEPROP 1 LAST WATTAGE 1/16W
J 2
(-1750 2875);
DISPLAY 0.617021 (-1750 2875);
PAINT SKYBLUE (-1750 2875);
FORCEPROP 1 LAST VALUE 49.9
J 2
(-1625 2875);
DISPLAY 0.617021 (-1625 2875);
PAINT SKYBLUE (-1625 2875);
FORCEPROP 1 LASTPIN (-1675 2925) $PN 1
J 0
(-1663 2937);
DISPLAY 0.617021 (-1663 2937);
PAINT ORANGE (-1663 2937);
FORCEPROP 1 LAST LOCATION R6D5
J 0
(-1625 2975);
DISPLAY 0.617021 (-1625 2975);
PAINT AQUA (-1625 2975);
FORCEPROP 1 LAST TOLERANCE 1%
J 0
(-1550 2875);
DISPLAY 0.617021 (-1550 2875);
PAINT SKYBLUE (-1550 2875);
FORCEPROP 1 LASTPIN (-1475 2925) $PN 2
J 0
(-1513 2937);
DISPLAY 0.617021 (-1513 2937);
PAINT ORANGE (-1513 2937);
FORCEPROP 1 LAST PART_NUMBER G21796-047
J 0
(-1450 2875);
DISPLAY 0.617021 (-1450 2875);
PAINT BLUE (-1450 2875);
FORCEPROP 2 LAST CDS_LIB mstr_discrete
J 0
(-1575 2925);
PAINT ORANGE (-1575 2925);
DISPLAY INVISIBLE (-1575 2925);
FORCEPROP 2 LAST CDS_LOCATION R6D5
J 0
(-1625 2975);
DISPLAY 0.617021 (-1625 2975);
PAINT AQUA (-1625 2975);
DISPLAY INVISIBLE (-1625 2975);
FORCEPROP 0 LAST ROOM CPU0
J 0
(-1625 3075);
DISPLAY 1.021277 (-1625 3075);
PAINT ORANGE (-1625 3075);
DISPLAY INVISIBLE (-1625 3075);
FORCEPROP 1 LAST PATH I81
J 0
(-1625 3075);
DISPLAY 0.978723 (-1625 3075);
PAINT WHITE (-1625 3075);
DISPLAY INVISIBLE (-1625 3075);
FORCEPROP 2 LAST SEC 1
J 0
(-1625 3125);
DISPLAY 0.680851 (-1625 3125);
PAINT MONO (-1625 3125);
DISPLAY INVISIBLE (-1625 3125);
FORCEPROP 2 LAST SEC_TYPE 0402
J 0
(-1625 3125);
DISPLAY 1.021277 (-1625 3125);
PAINT ORANGE (-1625 3125);
DISPLAY INVISIBLE (-1625 3125);
FORCEADD OFFPAGE..2
R 2
(-2800 3200);
FORCEPROP 2 LAST $XR0 21 
J 0
(-3024 3200);
DISPLAY 0.638298 (-3024 3200);
PAINT MONO (-3024 3200);
FORCEPROP 1 LAST OFFPAGE TRUE
J 2
(-3125 3075);
PAINT GREEN (-3125 3075);
DISPLAY INVISIBLE (-3125 3075);
FORCEPROP 2 LAST PATH I82
J 2
(-2975 3275);
DISPLAY 1.021277 (-2975 3275);
PAINT ORANGE (-2975 3275);
DISPLAY INVISIBLE (-2975 3275);
FORCEPROP 2 LAST CDS_LIB mstr_standard
J 2
(-2800 3200);
PAINT ORANGE (-2800 3200);
DISPLAY INVISIBLE (-2800 3200);
FORCEPROP 1 LAST COMMENT_BODY TRUE
J 2
(-2755 3105);
DISPLAY 1.170213 (-2755 3105);
PAINT GREEN (-2755 3105);
DISPLAY INVISIBLE (-2755 3105);
FORCEADD OFFPAGE..2
R 2
(-2800 3075);
FORCEPROP 2 LAST $XR0 21 
J 0
(-3024 3075);
DISPLAY 0.638298 (-3024 3075);
PAINT MONO (-3024 3075);
FORCEPROP 1 LAST OFFPAGE TRUE
J 2
(-3125 2950);
PAINT GREEN (-3125 2950);
DISPLAY INVISIBLE (-3125 2950);
FORCEPROP 1 LAST COMMENT_BODY TRUE
J 2
(-2755 2980);
DISPLAY 1.170213 (-2755 2980);
PAINT GREEN (-2755 2980);
DISPLAY INVISIBLE (-2755 2980);
FORCEPROP 2 LAST CDS_LIB mstr_standard
J 0
(-2800 3075);
PAINT ORANGE (-2800 3075);
DISPLAY INVISIBLE (-2800 3075);
FORCEPROP 2 LAST PATH I83
J 0
(-2750 3150);
DISPLAY 1.021277 (-2750 3150);
PAINT ORANGE (-2750 3150);
DISPLAY INVISIBLE (-2750 3150);
FORCEADD OFFPAGE..2
R 2
(-2800 2925);
FORCEPROP 2 LAST $XR0 21 
J 0
(-3024 2925);
DISPLAY 0.638298 (-3024 2925);
PAINT MONO (-3024 2925);
FORCEPROP 1 LAST OFFPAGE TRUE
J 2
(-3125 2800);
PAINT GREEN (-3125 2800);
DISPLAY INVISIBLE (-3125 2800);
FORCEPROP 2 LAST PATH I84
J 0
(-2750 3000);
DISPLAY 1.021277 (-2750 3000);
PAINT ORANGE (-2750 3000);
DISPLAY INVISIBLE (-2750 3000);
FORCEPROP 1 LAST COMMENT_BODY TRUE
J 2
(-2755 2830);
DISPLAY 1.170213 (-2755 2830);
PAINT GREEN (-2755 2830);
DISPLAY INVISIBLE (-2755 2830);
FORCEPROP 2 LAST CDS_LIB mstr_standard
J 0
(-2800 2925);
PAINT ORANGE (-2800 2925);
DISPLAY INVISIBLE (-2800 2925);
FORCEADD RES..1
(325 2475);
FORCEPROP 1 LAST PACK_TYPE 0402
J 0
(-250 2425);
DISPLAY 0.617021 (-250 2425);
PAINT SKYBLUE (-250 2425);
FORCEPROP 1 LAST MATERIAL CHIP
J 0
(-100 2425);
DISPLAY 0.617021 (-100 2425);
PAINT SKYBLUE (-100 2425);
FORCEPROP 1 LAST WATTAGE 1/16W
J 2
(150 2425);
DISPLAY 0.617021 (150 2425);
PAINT SKYBLUE (150 2425);
FORCEPROP 1 LAST VALUE 49.9
J 2
(275 2425);
DISPLAY 0.617021 (275 2425);
PAINT SKYBLUE (275 2425);
FORCEPROP 1 LASTPIN (225 2475) $PN 1
J 0
(237 2487);
DISPLAY 0.617021 (237 2487);
PAINT ORANGE (237 2487);
FORCEPROP 1 LAST LOCATION R8P1
J 0
(275 2525);
DISPLAY 0.617021 (275 2525);
PAINT AQUA (275 2525);
FORCEPROP 1 LAST TOLERANCE 1%
J 0
(350 2425);
DISPLAY 0.617021 (350 2425);
PAINT SKYBLUE (350 2425);
FORCEPROP 1 LASTPIN (425 2475) $PN 2
J 0
(387 2487);
DISPLAY 0.617021 (387 2487);
PAINT ORANGE (387 2487);
FORCEPROP 1 LAST PART_NUMBER G21796-047
J 0
(450 2425);
DISPLAY 0.617021 (450 2425);
PAINT BLUE (450 2425);
FORCEPROP 2 LAST CDS_LIB mstr_discrete
J 0
(325 2475);
PAINT ORANGE (325 2475);
DISPLAY INVISIBLE (325 2475);
FORCEPROP 2 LAST CDS_LOCATION R8P1
J 0
(275 2525);
DISPLAY 0.617021 (275 2525);
PAINT AQUA (275 2525);
DISPLAY INVISIBLE (275 2525);
FORCEPROP 2 LAST SEC_TYPE 0402
J 0
(275 2675);
DISPLAY 1.021277 (275 2675);
PAINT ORANGE (275 2675);
DISPLAY INVISIBLE (275 2675);
FORCEPROP 2 LAST SEC 1
J 0
(275 2675);
DISPLAY 0.680851 (275 2675);
PAINT MONO (275 2675);
DISPLAY INVISIBLE (275 2675);
FORCEPROP 1 LAST PATH I85
J 0
(275 2625);
DISPLAY 0.978723 (275 2625);
PAINT WHITE (275 2625);
DISPLAY INVISIBLE (275 2625);
FORCEPROP 0 LAST ROOM CPU1
J 0
(275 2625);
DISPLAY 1.021277 (275 2625);
PAINT ORANGE (275 2625);
DISPLAY INVISIBLE (275 2625);
FORCEADD RES..1
(325 2350);
FORCEPROP 1 LAST PACK_TYPE 0402
J 0
(-250 2300);
DISPLAY 0.617021 (-250 2300);
PAINT SKYBLUE (-250 2300);
FORCEPROP 1 LAST MATERIAL CHIP
J 0
(-100 2300);
DISPLAY 0.617021 (-100 2300);
PAINT SKYBLUE (-100 2300);
FORCEPROP 1 LAST WATTAGE 1/16W
J 2
(150 2300);
DISPLAY 0.617021 (150 2300);
PAINT SKYBLUE (150 2300);
FORCEPROP 1 LAST VALUE 49.9
J 2
(275 2300);
DISPLAY 0.617021 (275 2300);
PAINT SKYBLUE (275 2300);
FORCEPROP 1 LASTPIN (225 2350) $PN 1
J 0
(237 2362);
DISPLAY 0.617021 (237 2362);
PAINT ORANGE (237 2362);
FORCEPROP 1 LAST TOLERANCE 1%
J 0
(350 2300);
DISPLAY 0.617021 (350 2300);
PAINT SKYBLUE (350 2300);
FORCEPROP 1 LAST LOCATION R8P2
J 0
(275 2400);
DISPLAY 0.617021 (275 2400);
PAINT AQUA (275 2400);
FORCEPROP 1 LASTPIN (425 2350) $PN 2
J 0
(387 2362);
DISPLAY 0.617021 (387 2362);
PAINT ORANGE (387 2362);
FORCEPROP 1 LAST PART_NUMBER G21796-047
J 0
(450 2300);
DISPLAY 0.617021 (450 2300);
PAINT BLUE (450 2300);
FORCEPROP 2 LAST CDS_LIB mstr_discrete
J 0
(325 2350);
PAINT ORANGE (325 2350);
DISPLAY INVISIBLE (325 2350);
FORCEPROP 2 LAST CDS_LOCATION R8P2
J 0
(275 2400);
DISPLAY 0.617021 (275 2400);
PAINT AQUA (275 2400);
DISPLAY INVISIBLE (275 2400);
FORCEPROP 1 LAST PATH I86
J 0
(275 2500);
DISPLAY 0.978723 (275 2500);
PAINT WHITE (275 2500);
DISPLAY INVISIBLE (275 2500);
FORCEPROP 0 LAST ROOM CPU1
J 0
(275 2500);
DISPLAY 1.021277 (275 2500);
PAINT ORANGE (275 2500);
DISPLAY INVISIBLE (275 2500);
FORCEPROP 2 LAST SEC_TYPE 0402
J 0
(275 2550);
DISPLAY 1.021277 (275 2550);
PAINT ORANGE (275 2550);
DISPLAY INVISIBLE (275 2550);
FORCEPROP 2 LAST SEC 1
J 0
(275 2550);
DISPLAY 0.680851 (275 2550);
PAINT MONO (275 2550);
DISPLAY INVISIBLE (275 2550);
FORCEADD GND..1
(675 2000);
FORCEPROP 3 LASTPIN (675 2050) SIG_NAME GND\g
J 0
(685 2060);
DISPLAY 0.659574 (685 2060);
PAINT MONO (685 2060);
DISPLAY INVISIBLE (685 2060);
FORCEPROP 1 LAST VOLTAGE 0.0V
J 0
(630 1957);
DISPLAY 0.340426 (630 1957);
PAINT SKYBLUE (630 1957);
DISPLAY INVISIBLE (630 1957);
FORCEPROP 2 LAST CDS_LIB mstr_symbols
J 0
(675 2000);
PAINT ORANGE (675 2000);
DISPLAY INVISIBLE (675 2000);
FORCEPROP 1 LAST SIZE 1B
J 0
(750 1950);
DISPLAY 1.170213 (750 1950);
PAINT GREEN (750 1950);
DISPLAY INVISIBLE (750 1950);
FORCEPROP 1 LAST BODY_TYPE PLUMBING
J 0
(630 1957);
DISPLAY 0.340426 (630 1957);
PAINT GREEN (630 1957);
DISPLAY INVISIBLE (630 1957);
FORCEPROP 1 LAST PATH I87
J 0
(750 2000);
DISPLAY 0.872340 (750 2000);
PAINT AQUA (750 2000);
DISPLAY INVISIBLE (750 2000);
FORCEPROP 1 LAST HDL_POWER GND
J 0
(675 2150);
DISPLAY 0.702128 (675 2150);
PAINT GREEN (675 2150);
DISPLAY INVISIBLE (675 2150);
FORCEADD RES..1
(325 2200);
FORCEPROP 1 LAST PACK_TYPE 0402
J 0
(-250 2150);
DISPLAY 0.617021 (-250 2150);
PAINT SKYBLUE (-250 2150);
FORCEPROP 1 LAST MATERIAL CHIP
J 0
(-100 2150);
DISPLAY 0.617021 (-100 2150);
PAINT SKYBLUE (-100 2150);
FORCEPROP 1 LAST WATTAGE 1/16W
J 2
(150 2150);
DISPLAY 0.617021 (150 2150);
PAINT SKYBLUE (150 2150);
FORCEPROP 1 LAST VALUE 49.9
J 2
(275 2150);
DISPLAY 0.617021 (275 2150);
PAINT SKYBLUE (275 2150);
FORCEPROP 1 LASTPIN (225 2200) $PN 1
J 0
(237 2212);
DISPLAY 0.617021 (237 2212);
PAINT ORANGE (237 2212);
FORCEPROP 1 LAST LOCATION R3D9
J 0
(275 2250);
DISPLAY 0.617021 (275 2250);
PAINT AQUA (275 2250);
FORCEPROP 1 LAST TOLERANCE 1%
J 0
(350 2150);
DISPLAY 0.617021 (350 2150);
PAINT SKYBLUE (350 2150);
FORCEPROP 1 LASTPIN (425 2200) $PN 2
J 0
(387 2212);
DISPLAY 0.617021 (387 2212);
PAINT ORANGE (387 2212);
FORCEPROP 1 LAST PART_NUMBER G21796-047
J 0
(450 2150);
DISPLAY 0.617021 (450 2150);
PAINT BLUE (450 2150);
FORCEPROP 2 LAST CDS_LIB mstr_discrete
J 0
(325 2200);
PAINT ORANGE (325 2200);
DISPLAY INVISIBLE (325 2200);
FORCEPROP 2 LAST CDS_LOCATION R3D9
J 0
(275 2250);
DISPLAY 0.617021 (275 2250);
PAINT AQUA (275 2250);
DISPLAY INVISIBLE (275 2250);
FORCEPROP 2 LAST SEC 1
J 0
(275 2400);
DISPLAY 0.680851 (275 2400);
PAINT MONO (275 2400);
DISPLAY INVISIBLE (275 2400);
FORCEPROP 1 LAST PATH I88
J 0
(275 2350);
DISPLAY 0.978723 (275 2350);
PAINT WHITE (275 2350);
DISPLAY INVISIBLE (275 2350);
FORCEPROP 0 LAST ROOM CPU1
J 0
(275 2350);
DISPLAY 1.021277 (275 2350);
PAINT ORANGE (275 2350);
DISPLAY INVISIBLE (275 2350);
FORCEPROP 2 LAST SEC_TYPE 0402
J 0
(275 2400);
DISPLAY 1.021277 (275 2400);
PAINT ORANGE (275 2400);
DISPLAY INVISIBLE (275 2400);
FORCEADD OFFPAGE..2
R 2
(-900 2475);
FORCEPROP 2 LAST $XR0 55 
J 0
(-1124 2475);
DISPLAY 0.638298 (-1124 2475);
PAINT MONO (-1124 2475);
FORCEPROP 1 LAST OFFPAGE TRUE
J 2
(-1225 2350);
PAINT GREEN (-1225 2350);
DISPLAY INVISIBLE (-1225 2350);
FORCEPROP 2 LAST CDS_LIB mstr_standard
J 2
(-900 2475);
PAINT ORANGE (-900 2475);
DISPLAY INVISIBLE (-900 2475);
FORCEPROP 1 LAST COMMENT_BODY TRUE
J 2
(-855 2380);
DISPLAY 1.170213 (-855 2380);
PAINT GREEN (-855 2380);
DISPLAY INVISIBLE (-855 2380);
FORCEPROP 2 LAST PATH I89
J 0
(-850 2550);
DISPLAY 1.021277 (-850 2550);
PAINT ORANGE (-850 2550);
DISPLAY INVISIBLE (-850 2550);
FORCEADD OFFPAGE..2
(550 1275);
FORCEPROP 2 LAST $XR0 55 
J 0
(739 1275);
DISPLAY 0.638298 (739 1275);
PAINT MONO (739 1275);
FORCEPROP 1 LAST COMMENT_BODY TRUE
J 0
(505 1180);
DISPLAY 1.170213 (505 1180);
PAINT GREEN (505 1180);
DISPLAY INVISIBLE (505 1180);
FORCEPROP 2 LAST CDS_LIB mstr_standard
J 0
(550 1275);
PAINT ORANGE (550 1275);
DISPLAY INVISIBLE (550 1275);
FORCEPROP 2 LAST PATH I9
J 0
(750 1325);
DISPLAY 1.021277 (750 1325);
PAINT ORANGE (750 1325);
DISPLAY INVISIBLE (750 1325);
FORCEPROP 1 LAST OFFPAGE TRUE
J 0
(875 1150);
PAINT GREEN (875 1150);
DISPLAY INVISIBLE (875 1150);
FORCEADD OFFPAGE..2
R 2
(-900 2350);
FORCEPROP 2 LAST $XR0 55 
J 0
(-1124 2350);
DISPLAY 0.638298 (-1124 2350);
PAINT MONO (-1124 2350);
FORCEPROP 1 LAST OFFPAGE TRUE
J 2
(-1225 2225);
PAINT GREEN (-1225 2225);
DISPLAY INVISIBLE (-1225 2225);
FORCEPROP 1 LAST COMMENT_BODY TRUE
J 2
(-855 2255);
DISPLAY 1.170213 (-855 2255);
PAINT GREEN (-855 2255);
DISPLAY INVISIBLE (-855 2255);
FORCEPROP 2 LAST CDS_LIB mstr_standard
J 0
(-900 2350);
PAINT ORANGE (-900 2350);
DISPLAY INVISIBLE (-900 2350);
FORCEPROP 2 LAST PATH I90
J 0
(-850 2425);
DISPLAY 1.021277 (-850 2425);
PAINT ORANGE (-850 2425);
DISPLAY INVISIBLE (-850 2425);
FORCEADD OFFPAGE..2
R 2
(-900 2200);
FORCEPROP 2 LAST $XR0 55 
J 0
(-1124 2200);
DISPLAY 0.638298 (-1124 2200);
PAINT MONO (-1124 2200);
FORCEPROP 1 LAST OFFPAGE TRUE
J 2
(-1225 2075);
PAINT GREEN (-1225 2075);
DISPLAY INVISIBLE (-1225 2075);
FORCEPROP 1 LAST COMMENT_BODY TRUE
J 2
(-855 2105);
DISPLAY 1.170213 (-855 2105);
PAINT GREEN (-855 2105);
DISPLAY INVISIBLE (-855 2105);
FORCEPROP 2 LAST CDS_LIB mstr_standard
J 0
(-900 2200);
PAINT ORANGE (-900 2200);
DISPLAY INVISIBLE (-900 2200);
FORCEPROP 2 LAST PATH I91
J 0
(-850 2275);
DISPLAY 1.021277 (-850 2275);
PAINT ORANGE (-850 2275);
DISPLAY INVISIBLE (-850 2275);
FORCEADD DNS..2
(-320 1045);
PAINT RED (-320 1045);
FORCEPROP 1 LAST COMMENT_BODY TRUE
R 1
J 0
(-245 820);
DISPLAY 0.872340 (-245 820);
PAINT GREEN (-245 820);
DISPLAY INVISIBLE (-245 820);
FORCEPROP 2 LAST CDS_LIB mstr_misc
J 0
(-320 1045);
PAINT ORANGE (-320 1045);
DISPLAY INVISIBLE (-320 1045);
FORCEADD DNS..2
(-2420 1270);
PAINT RED (-2420 1270);
FORCEPROP 1 LAST COMMENT_BODY TRUE
R 1
J 0
(-2345 1045);
DISPLAY 0.872340 (-2345 1045);
PAINT GREEN (-2345 1045);
DISPLAY INVISIBLE (-2345 1045);
FORCEPROP 2 LAST CDS_LIB mstr_misc
J 0
(-2420 1270);
PAINT ORANGE (-2420 1270);
DISPLAY INVISIBLE (-2420 1270);
FORCEADD DNS..2
(-2470 4195);
PAINT RED (-2470 4195);
FORCEPROP 1 LAST COMMENT_BODY TRUE
R 1
J 0
(-2395 3970);
DISPLAY 0.872340 (-2395 3970);
PAINT GREEN (-2395 3970);
DISPLAY INVISIBLE (-2395 3970);
FORCEPROP 2 LAST CDS_LIB mstr_misc
J 0
(-2470 4195);
PAINT ORANGE (-2470 4195);
DISPLAY INVISIBLE (-2470 4195);
FORCEADD DNS..2
(-2470 3995);
PAINT RED (-2470 3995);
FORCEPROP 1 LAST COMMENT_BODY TRUE
R 1
J 0
(-2395 3770);
DISPLAY 0.872340 (-2395 3770);
PAINT GREEN (-2395 3770);
DISPLAY INVISIBLE (-2395 3770);
FORCEPROP 2 LAST CDS_LIB mstr_misc
J 0
(-2470 3995);
PAINT ORANGE (-2470 3995);
DISPLAY INVISIBLE (-2470 3995);
FORCEADD DNS..2
(-2445 1670);
PAINT RED (-2445 1670);
FORCEPROP 1 LAST COMMENT_BODY TRUE
R 1
J 0
(-2370 1445);
DISPLAY 0.872340 (-2370 1445);
PAINT GREEN (-2370 1445);
DISPLAY INVISIBLE (-2370 1445);
FORCEPROP 2 LAST CDS_LIB mstr_misc
J 0
(-2445 1670);
PAINT ORANGE (-2445 1670);
DISPLAY INVISIBLE (-2445 1670);
FORCEADD DNS..2
(-2445 1870);
PAINT RED (-2445 1870);
FORCEPROP 1 LAST COMMENT_BODY TRUE
R 1
J 0
(-2370 1645);
DISPLAY 0.872340 (-2370 1645);
PAINT GREEN (-2370 1645);
DISPLAY INVISIBLE (-2370 1645);
FORCEPROP 2 LAST CDS_LIB mstr_misc
J 0
(-2445 1870);
PAINT ORANGE (-2445 1870);
DISPLAY INVISIBLE (-2445 1870);
FORCEADD DNS..2
(-2495 3795);
PAINT RED (-2495 3795);
FORCEPROP 1 LAST COMMENT_BODY TRUE
R 1
J 0
(-2420 3570);
DISPLAY 0.872340 (-2420 3570);
PAINT GREEN (-2420 3570);
DISPLAY INVISIBLE (-2420 3570);
FORCEPROP 2 LAST CDS_LIB mstr_misc
J 0
(-2495 3795);
PAINT ORANGE (-2495 3795);
DISPLAY INVISIBLE (-2495 3795);
FORCEADD DNS..2
(-495 3195);
PAINT RED (-495 3195);
FORCEPROP 1 LAST COMMENT_BODY TRUE
R 1
J 0
(-420 2970);
DISPLAY 0.872340 (-420 2970);
PAINT GREEN (-420 2970);
DISPLAY INVISIBLE (-420 2970);
FORCEPROP 2 LAST CDS_LIB mstr_misc
J 0
(-495 3195);
PAINT ORANGE (-495 3195);
DISPLAY INVISIBLE (-495 3195);
FORCEADD DNS..2
(-295 4395);
PAINT RED (-295 4395);
FORCEPROP 1 LAST COMMENT_BODY TRUE
R 1
J 0
(-220 4170);
DISPLAY 0.872340 (-220 4170);
PAINT GREEN (-220 4170);
DISPLAY INVISIBLE (-220 4170);
FORCEPROP 2 LAST CDS_LIB mstr_misc
J 0
(-295 4395);
PAINT ORANGE (-295 4395);
DISPLAY INVISIBLE (-295 4395);
FORCEADD DNS..2
(-295 4195);
PAINT RED (-295 4195);
FORCEPROP 1 LAST COMMENT_BODY TRUE
R 1
J 0
(-220 3970);
DISPLAY 0.872340 (-220 3970);
PAINT GREEN (-220 3970);
DISPLAY INVISIBLE (-220 3970);
FORCEPROP 2 LAST CDS_LIB mstr_misc
J 0
(-295 4195);
PAINT ORANGE (-295 4195);
DISPLAY INVISIBLE (-295 4195);
FORCEADD DNS..2
(-2445 1470);
PAINT RED (-2445 1470);
FORCEPROP 1 LAST COMMENT_BODY TRUE
R 1
J 0
(-2370 1245);
DISPLAY 0.872340 (-2370 1245);
PAINT GREEN (-2370 1245);
DISPLAY INVISIBLE (-2370 1245);
FORCEPROP 2 LAST CDS_LIB mstr_misc
J 0
(-2445 1470);
PAINT ORANGE (-2445 1470);
DISPLAY INVISIBLE (-2445 1470);
FORCEADD CAD_NOTE..1
(-2425 2825);
FORCEPROP 0 LAST L1 PLACE PD WITHIN 500 MILS OF CPU0
J 2
(-1725 2700);
DISPLAY 1.021277 (-1725 2700);
PAINT ORANGE (-1725 2700);
FORCEPROP 1 LAST COMMENT_BODY TRUE
J 0
(-2400 2925);
DISPLAY 0.978723 (-2400 2925);
PAINT ORANGE (-2400 2925);
DISPLAY INVISIBLE (-2400 2925);
FORCEPROP 2 LAST CDS_LIB mstr_symbols
J 0
(-2425 2825);
PAINT ORANGE (-2425 2825);
DISPLAY INVISIBLE (-2425 2825);
FORCEADD CAD_NOTE..1
(-525 2100);
FORCEPROP 0 LAST L1 PLACE PD WITHIN 500 MILS OF CPU1
J 2
(475 1975);
DISPLAY 1.021277 (475 1975);
PAINT ORANGE (475 1975);
FORCEPROP 2 LAST CDS_LIB mstr_symbols
J 0
(-525 2100);
PAINT ORANGE (-525 2100);
DISPLAY INVISIBLE (-525 2100);
FORCEPROP 1 LAST COMMENT_BODY TRUE
J 0
(-500 2200);
DISPLAY 0.978723 (-500 2200);
PAINT ORANGE (-500 2200);
DISPLAY INVISIBLE (-500 2200);
FORCEADD DESIGN_NOTE..1
(-650 3875);
PAINT PURPLE (-650 3875);
FORCEPROP 0 LAST L3 WHEN TXT IS READY
J 0
(-850 3625);
PAINT VIOLET (-850 3625);
FORCEPROP 0 LAST L1 ***TXT IS DISABLED FOR EARLY SILICON
J 0
(-850 3750);
PAINT VIOLET (-850 3750);
FORCEPROP 0 LAST L2 ENABLE ACCORDING TO TABLE
J 0
(-850 3700);
PAINT VIOLET (-850 3700);
FORCEPROP 2 LAST CDS_LIB mstr_symbols
J 0
(-650 3875);
PAINT ORANGE (-650 3875);
DISPLAY INVISIBLE (-650 3875);
FORCEPROP 2 LAST BOM_COST SM_CONTROLLER
J 0
(-850 3825);
PAINT MONO (-850 3825);
DISPLAY INVISIBLE (-850 3825);
FORCEPROP 1 LAST COMMENT_BODY TRUE
J 0
(-625 3975);
DISPLAY 1.319149 (-625 3975);
PAINT GREEN (-625 3975);
DISPLAY INVISIBLE (-625 3975);
FORCEPROP 2 LAST ROOM PVCCIN_CPU1_DECAP_VR
J 0
(-850 3825);
PAINT MONO (-850 3825);
DISPLAY INVISIBLE (-850 3825);
FORCEADD DNS..2
(-2470 3595);
PAINT RED (-2470 3595);
FORCEPROP 1 LAST COMMENT_BODY TRUE
R 1
J 0
(-2395 3370);
DISPLAY 0.872340 (-2395 3370);
PAINT GREEN (-2395 3370);
DISPLAY INVISIBLE (-2395 3370);
FORCEPROP 2 LAST CDS_LIB mstr_misc
J 0
(-2470 3595);
PAINT ORANGE (-2470 3595);
DISPLAY INVISIBLE (-2470 3595);
FORCEADD DNS..2
(-345 1470);
PAINT RED (-345 1470);
FORCEPROP 1 LAST COMMENT_BODY TRUE
R 1
J 0
(-270 1245);
DISPLAY 0.872340 (-270 1245);
PAINT GREEN (-270 1245);
DISPLAY INVISIBLE (-270 1245);
FORCEPROP 2 LAST CDS_LIB mstr_misc
J 0
(-345 1470);
PAINT ORANGE (-345 1470);
DISPLAY INVISIBLE (-345 1470);
FORCEADD DNS..2
(-2495 1020);
PAINT RED (-2495 1020);
FORCEPROP 1 LAST COMMENT_BODY TRUE
R 1
J 0
(-2420 795);
DISPLAY 0.872340 (-2420 795);
PAINT GREEN (-2420 795);
DISPLAY INVISIBLE (-2420 795);
FORCEPROP 2 LAST CDS_LIB mstr_misc
J 0
(-2495 1020);
PAINT ORANGE (-2495 1020);
DISPLAY INVISIBLE (-2495 1020);
FORCEADD DNS..2
(-420 2995);
PAINT RED (-420 2995);
FORCEPROP 1 LAST COMMENT_BODY TRUE
R 1
J 0
(-345 2770);
DISPLAY 0.872340 (-345 2770);
PAINT GREEN (-345 2770);
DISPLAY INVISIBLE (-345 2770);
FORCEPROP 2 LAST CDS_LIB mstr_misc
J 0
(-420 2995);
PAINT ORANGE (-420 2995);
DISPLAY INVISIBLE (-420 2995);
FORCEADD DNS..2
(-420 2795);
PAINT RED (-420 2795);
FORCEPROP 1 LAST COMMENT_BODY TRUE
R 1
J 0
(-345 2570);
DISPLAY 0.872340 (-345 2570);
PAINT GREEN (-345 2570);
DISPLAY INVISIBLE (-345 2570);
FORCEPROP 2 LAST CDS_LIB mstr_misc
J 0
(-420 2795);
PAINT ORANGE (-420 2795);
DISPLAY INVISIBLE (-420 2795);
FORCEADD DNS..2
(-270 645);
PAINT RED (-270 645);
FORCEPROP 1 LAST COMMENT_BODY TRUE
R 1
J 0
(-195 420);
DISPLAY 0.872340 (-195 420);
PAINT GREEN (-195 420);
DISPLAY INVISIBLE (-195 420);
FORCEPROP 2 LAST CDS_LIB mstr_misc
J 0
(-270 645);
PAINT ORANGE (-270 645);
DISPLAY INVISIBLE (-270 645);
FORCEADD DNS..2
(-2470 795);
PAINT RED (-2470 795);
FORCEPROP 1 LAST COMMENT_BODY TRUE
R 1
J 0
(-2395 570);
DISPLAY 0.872340 (-2395 570);
PAINT GREEN (-2395 570);
DISPLAY INVISIBLE (-2395 570);
FORCEPROP 2 LAST CDS_LIB mstr_misc
J 0
(-2470 795);
PAINT ORANGE (-2470 795);
DISPLAY INVISIBLE (-2470 795);
FORCEADD INTEL_CORP_BPAGE..1
(4250 200);
FORCEPROP 1 LAST CDS_CON_LAST_MODIFIED Tue Dec 01 11:51:47 2015
J 0
(2825 525);
PAINT ORANGE (2825 525);
DISPLAY INVISIBLE (2825 525);
FORCEPROP 1 LAST CUSTOM_TXT_CDS <CURRENT_DESIGN_SHEET> OF <TOTAL_DESIGN_SHEETS>
J 0
(3750 225);
PAINT GREEN (3750 225);
FORCEPROP 1 LAST CUSTOM_TXT_CDS <CON_LAST_MODIFIED>
J 0
(2325 550);
PAINT GREEN (2325 550);
FORCEPROP 2 LAST CUSTOM_TXT_CDS <XR_PAGE_TITLE>
J 0
(-3640 5450);
DISPLAY 0.638298 (-3640 5450);
PAINT PINK (-3640 5450);
DISPLAY INVISIBLE (-3640 5450);
FORCEPROP 1 LAST SCH_TITLE CPU SIDE BAND: HW STRAPS
J 0
(-3700 250);
DISPLAY 1.212766 (-3700 250);
PAINT ORANGE (-3700 250);
FORCEPROP 1 LAST SCH_ADDRESS2 P.O. BOX 58119
J 0
(275 275);
DISPLAY 0.617021 (275 275);
PAINT GREEN (275 275);
FORCEPROP 1 LAST SCH_ADDRESS3 Santa Clara, CA 95052-8119
J 0
(275 225);
DISPLAY 0.617021 (275 225);
PAINT GREEN (275 225);
FORCEPROP 1 LAST SCH_ADDRESS1 2200 Mission College Blvd.
J 0
(275 325);
DISPLAY 0.617021 (275 325);
PAINT GREEN (275 325);
FORCEPROP 1 LAST SCH_NUMBER H4694802
J 0
(2950 350);
DISPLAY 1.212766 (2950 350);
PAINT YELLOW (2950 350);
FORCEPROP 1 LAST SCH_DEPT BESD
J 1
(-200 300);
DISPLAY 1.212766 (-200 300);
PAINT YELLOW (-200 300);
FORCEPROP 1 LAST SCH_REV 2.420
J 0
(4000 350);
DISPLAY 0.978723 (4000 350);
PAINT YELLOW (4000 350);
FORCEPROP 2 LAST PAGE_BORDER TRUE
J 0
(-3640 5450);
DISPLAY 0.638298 (-3640 5450);
PAINT PINK (-3640 5450);
DISPLAY INVISIBLE (-3640 5450);
FORCEPROP 2 LAST CDS_LIB mstr_symbols
J 0
(4250 200);
PAINT MONO (4250 200);
DISPLAY INVISIBLE (4250 200);
FORCEPROP 1 LAST COMMENT_BODY TRUE
J 0
(4262 212);
DISPLAY 0.468085 (4262 212);
PAINT GREEN (4262 212);
DISPLAY INVISIBLE (4262 212);
FORCEPROP 2 LAST CDS_XR_PAGE_TITLE CR-90 : @BASEBOARD_FAB2_LIB.BASEBOARD_FAB2(SCH_1):PAGE90
J 0
(-3640 5450);
DISPLAY 0.638298 (-3640 5450);
PAINT PINK (-3640 5450);
DISPLAY INVISIBLE (-3640 5450);
WIRE 16 -1 (-425 1275)(-725 1275);
WIRE 16 -1 (-725 1275)(-725 1050);
WIRE 16 -1 (-425 1050)(-725 1050);
WIRE 16 -1 (-725 1050)(-725 850);
WIRE 16 -1 (-725 850)(-375 850);
WIRE 16 -1 (-725 850)(-725 650);
WIRE 16 -1 (-725 650)(-375 650);
WIRE 16 -1 (-725 650)(-725 575);
WIRE 16 -1 (-2975 3600)(-2975 3400);
WIRE 16 -1 (-2975 3600)(-2575 3600);
WIRE 16 -1 (-2975 3800)(-2975 3600);
WIRE 16 -1 (-2975 3400)(-2600 3400);
WIRE 16 -1 (-2975 3800)(-2600 3800);
WIRE 16 -1 (-2975 4000)(-2975 3800);
WIRE 16 -1 (-2975 4000)(-2975 4200);
WIRE 16 -1 (-2975 4000)(-2575 4000);
WIRE 16 -1 (-2975 4200)(-2575 4200);
WIRE 16 -1 (-2975 4200)(-2975 4400);
WIRE 16 -1 (-2975 4400)(-2575 4400);
WIRE 16 -1 (-2975 4400)(-2975 4500);
WIRE 16 -1 (-600 3400)(-900 3400);
WIRE 16 -1 (-900 3400)(-900 3200);
WIRE 16 -1 (-600 3200)(-900 3200);
WIRE 16 -1 (-900 3000)(-900 3200);
WIRE 16 -1 (-900 3000)(-525 3000);
WIRE 16 -1 (-900 3000)(-900 2800);
WIRE 16 -1 (-900 2800)(-525 2800);
WIRE 16 -1 (-900 2650)(-900 2800);
WIRE 16 -1 (-400 4200)(-825 4200);
WIRE 16 -1 (-825 4200)(-825 4400);
WIRE 16 -1 (-400 4400)(-825 4400);
WIRE 16 -1 (-825 4575)(-825 4400);
WIRE 16 -1 (-2950 1025)(-2950 800);
WIRE 16 -1 (-2950 1025)(-2600 1025);
WIRE 16 -1 (-2950 1275)(-2950 1025);
WIRE 16 -1 (-2950 800)(-2575 800);
WIRE 16 -1 (-2950 1275)(-2525 1275);
WIRE 16 -1 (-2950 1475)(-2950 1275);
WIRE 16 -1 (-2950 1475)(-2550 1475);
WIRE 16 -1 (-2950 1675)(-2950 1475);
WIRE 16 -1 (-2950 1675)(-2550 1675);
WIRE 16 -1 (-2950 1875)(-2950 1675);
WIRE 16 -1 (-2950 1875)(-2550 1875);
WIRE 16 -1 (-2950 2000)(-2950 1875);
WIRE 16 -1 (-450 1475)(-725 1475);
WIRE 16 -1 (-725 1675)(-725 1475);
WIRE 16 -1 (-475 1675)(-725 1675);
WIRE 16 -1 (-725 1775)(-725 1675);
WIRE 16 -1 (-1475 3200)(-1225 3200);
WIRE 16 -1 (-1225 3075)(-1225 3200);
WIRE 16 -1 (-1475 3075)(-1225 3075);
WIRE 16 -1 (-1225 2925)(-1225 3075);
WIRE 16 -1 (-1475 2925)(-1225 2925);
WIRE 16 -1 (-1225 2925)(-1225 2775);
WIRE 16 -1 (425 2475)(675 2475);
WIRE 16 -1 (675 2350)(675 2475);
WIRE 16 -1 (425 2350)(675 2350);
WIRE 16 -1 (675 2200)(675 2350);
WIRE 16 -1 (425 2200)(675 2200);
WIRE 16 -1 (675 2200)(675 2050);
WIRE 16 -1 (-3500 4800)(-2425 4800);
WIRE 16 -1 (-3500 5000)(-3500 4800);
WIRE 16 -1 (-2425 5000)(-2425 4800);
WIRE 16 -1 (-2425 5000)(-3500 5000);
WIRE 16 -1 (-1675 2925)(-2750 2925);
FORCEPROP 2 LAST SIG_NAME PD_CPU0_TEST12
J 0
(-2700 2935);
DISPLAY 0.617021 (-2700 2935);
PAINT ORANGE (-2700 2935);
WIRE 16 273 (1000 3150)(4125 3150);
WIRE 16 273 (4125 3700)(4125 3150);
WIRE 16 273 (4125 3150)(4125 2825);
WIRE 16 273 (4125 2825)(4125 2600);
WIRE 16 273 (1000 2825)(4125 2825);
WIRE 16 273 (4125 4125)(4125 3700);
WIRE 16 273 (1000 3700)(4125 3700);
WIRE 16 273 (925 4125)(4125 4125);
WIRE 16 273 (4125 2600)(4125 2375);
WIRE 16 273 (1000 2600)(4125 2600);
WIRE 16 273 (4125 2375)(4125 2150);
WIRE 16 273 (1000 2375)(4125 2375);
WIRE 16 273 (925 1125)(925 4125);
WIRE 16 273 (4125 1125)(925 1125);
WIRE 16 273 (4125 2150)(4125 1925);
WIRE 16 273 (1000 2150)(4125 2150);
WIRE 16 273 (4125 1925)(4125 1125);
WIRE 16 273 (1000 1925)(4125 1925);
WIRE 16 273 (1000 3475)(4100 3475);
WIRE 16 273 (1000 3925)(4100 3925);
WIRE 16 273 (1000 1700)(4100 1700);
WIRE 16 273 (2575 4100)(2575 1150);
WIRE 16 273 (2300 4100)(2300 1150);
WIRE 16 273 (1725 4100)(1725 1150);
WIRE 16 273 (2000 4100)(2000 1150);
WIRE 16 273 (975 1425)(4075 1425);
WIRE 16 -1 (225 2200)(-850 2200);
FORCEPROP 2 LAST SIG_NAME PD_CPU1_TEST12
J 0
(-800 2210);
DISPLAY 0.617021 (-800 2210);
PAINT ORANGE (-800 2210);
WIRE 16 -1 (225 2350)(-850 2350);
FORCEPROP 2 LAST SIG_NAME PD_CPU1_TEST13
J 0
(-775 2360);
DISPLAY 0.617021 (-775 2360);
PAINT ORANGE (-775 2360);
WIRE 16 -1 (-850 2475)(225 2475);
FORCEPROP 2 LAST SIG_NAME PD_CPU1_TEST14
J 0
(-775 2485);
DISPLAY 0.617021 (-775 2485);
PAINT ORANGE (-775 2485);
WIRE 16 -1 (-325 3000)(425 3000);
FORCEPROP 2 LAST SIG_NAME PD_CPU0_DMIMODE_OVERRIDE
J 0
(-235 3010);
DISPLAY 0.617021 (-235 3010);
PAINT ORANGE (-235 3010);
WIRE 16 -1 (475 4200)(-200 4200);
FORCEPROP 2 LAST SIG_NAME PU_CPU0_SOCKET_ID_1
J 0
(-110 4210);
DISPLAY 0.617021 (-110 4210);
PAINT ORANGE (-110 4210);
WIRE 16 -1 (475 4400)(-200 4400);
FORCEPROP 2 LAST SIG_NAME PU_CPU0_SOCKET_ID_0
J 0
(-110 4410);
DISPLAY 0.617021 (-110 4410);
PAINT ORANGE (-110 4410);
WIRE 16 -1 (-325 2800)(425 2800);
FORCEPROP 2 LAST SIG_NAME PD_CPU0_KSFC_DIS
J 0
(-215 2802);
DISPLAY 0.617021 (-215 2802);
PAINT ORANGE (-215 2802);
WIRE 16 -1 (425 3200)(-400 3200);
FORCEPROP 2 LAST SIG_NAME PD_CPU0_BIST_ENABLE
J 0
(-260 3210);
DISPLAY 0.617021 (-260 3210);
PAINT ORANGE (-260 3210);
WIRE 16 -1 (425 3400)(-400 3400);
FORCEPROP 2 LAST SIG_NAME PD_CPU0_TXT_PLTEN
J 0
(-210 3410);
DISPLAY 0.617021 (-210 3410);
PAINT ORANGE (-210 3410);
WIRE 16 -1 (450 1675)(-275 1675);
FORCEPROP 2 LAST SIG_NAME PU_CPU1_SOCKET_ID_0
J 0
(15 1685);
DISPLAY 0.617021 (15 1685);
PAINT ORANGE (15 1685);
WIRE 16 -1 (450 1475)(-250 1475);
FORCEPROP 2 LAST SIG_NAME PU_CPU1_SOCKET_ID_1
J 0
(40 1485);
DISPLAY 0.617021 (40 1485);
PAINT ORANGE (40 1485);
WIRE 16 -1 (500 1050)(-225 1050);
FORCEPROP 2 LAST SIG_NAME PD_CPU1_BIST_ENABLE
J 0
(-35 1060);
DISPLAY 0.617021 (-35 1060);
PAINT ORANGE (-35 1060);
WIRE 16 -1 (-175 650)(625 650);
FORCEPROP 2 LAST SIG_NAME PD_CPU1_KSFC_DIS
J 0
(-65 652);
DISPLAY 0.617021 (-65 652);
PAINT ORANGE (-65 652);
WIRE 16 -1 (-175 850)(625 850);
FORCEPROP 2 LAST SIG_NAME PD_CPU1_DMIMODE_OVERRIDE
J 0
(-60 860);
DISPLAY 0.617021 (-60 860);
PAINT ORANGE (-60 860);
WIRE 16 -1 (500 1275)(-225 1275);
FORCEPROP 2 LAST SIG_NAME PD_CPU1_TXT_PLTEN
J 0
(15 1285);
DISPLAY 0.617021 (15 1285);
PAINT ORANGE (15 1285);
WIRE 16 -1 (-1350 4400)(-2375 4400);
FORCEPROP 2 LAST SIG_NAME PU_CPU0_FRMAGENT
J 0
(-2060 4410);
DISPLAY 0.617021 (-2060 4410);
PAINT ORANGE (-2060 4410);
WIRE 16 -1 (-1350 4200)(-2375 4200);
FORCEPROP 2 LAST SIG_NAME H_CPU0_BMCINIT
J 0
(-2060 4210);
DISPLAY 0.617021 (-2060 4210);
PAINT ORANGE (-2060 4210);
WIRE 16 -1 (-2400 5025)(-2400 4775);
WIRE 16 -1 (-2400 5025)(-3525 5025);
WIRE 16 -1 (-2400 4775)(-3525 4775);
WIRE 16 -1 (-3525 5025)(-3525 4775);
WIRE 16 -1 (-1675 3075)(-2750 3075);
FORCEPROP 2 LAST SIG_NAME PD_CPU0_TEST13
J 0
(-2675 3085);
DISPLAY 0.617021 (-2675 3085);
PAINT ORANGE (-2675 3085);
WIRE 16 -1 (-1350 3400)(-2400 3400);
FORCEPROP 2 LAST SIG_NAME PU_CPU0_LEGACY_SKT
J 0
(-2060 3410);
DISPLAY 0.617021 (-2060 3410);
PAINT ORANGE (-2060 3410);
WIRE 16 -1 (-2375 4000)(-1350 4000);
FORCEPROP 2 LAST SIG_NAME PU_CPU0_TXT_AGENT
J 0
(-2085 4010);
DISPLAY 0.617021 (-2085 4010);
PAINT ORANGE (-2085 4010);
WIRE 16 -1 (-2750 3200)(-1675 3200);
FORCEPROP 2 LAST SIG_NAME PD_CPU0_TEST14
J 0
(-2675 3210);
DISPLAY 0.617021 (-2675 3210);
PAINT ORANGE (-2675 3210);
WIRE 16 -1 (-2375 3600)(-1350 3600);
FORCEPROP 2 LAST SIG_NAME PU_CPU0_EAR_N
J 0
(-2060 3610);
DISPLAY 0.617021 (-2060 3610);
PAINT ORANGE (-2060 3610);
WIRE 16 -1 (-1350 3800)(-2400 3800);
FORCEPROP 2 LAST SIG_NAME PU_CPU0_SAFE_MODE_BOOT
J 0
(-2135 3810);
DISPLAY 0.617021 (-2135 3810);
PAINT ORANGE (-2135 3810);
WIRE 16 -1 (-2400 1025)(-1375 1025);
FORCEPROP 2 LAST SIG_NAME PU_CPU1_EAR_N
J 0
(-2060 1035);
DISPLAY 0.617021 (-2060 1035);
PAINT ORANGE (-2060 1035);
WIRE 16 -1 (-1400 1275)(-2325 1275);
FORCEPROP 2 LAST SIG_NAME PU_CPU1_SAFE_MODE_BOOT
J 0
(-2060 1285);
DISPLAY 0.617021 (-2060 1285);
PAINT ORANGE (-2060 1285);
WIRE 16 -1 (-1400 1675)(-2350 1675);
FORCEPROP 2 LAST SIG_NAME H_CPU1_BMCINIT
J 0
(-2060 1685);
DISPLAY 0.617021 (-2060 1685);
PAINT ORANGE (-2060 1685);
WIRE 16 -1 (-1400 1475)(-2350 1475);
FORCEPROP 2 LAST SIG_NAME PU_CPU1_TXT_AGENT
J 0
(-2060 1485);
DISPLAY 0.617021 (-2060 1485);
PAINT ORANGE (-2060 1485);
WIRE 16 -1 (-2375 800)(-1375 800);
FORCEPROP 2 LAST SIG_NAME PU_CPU1_LEGACY_SKT
J 0
(-2060 810);
DISPLAY 0.617021 (-2060 810);
PAINT ORANGE (-2060 810);
WIRE 16 -1 (-1400 1875)(-2350 1875);
FORCEPROP 2 LAST SIG_NAME PU_CPU1_FRMAGENT
J 0
(-2060 1885);
DISPLAY 0.617021 (-2060 1885);
PAINT ORANGE (-2060 1885);
WIRE 16 -1 (-2400 2550)(-2400 2300);
WIRE 16 -1 (-2400 2550)(-3525 2550);
WIRE 16 -1 (-2400 2300)(-3525 2300);
WIRE 16 -1 (-3525 2550)(-3525 2300);
WIRE 16 -1 (-2425 2525)(-2425 2325);
WIRE 16 -1 (-2425 2525)(-3500 2525);
WIRE 16 -1 (-3500 2325)(-2425 2325);
WIRE 16 -1 (-3500 2525)(-3500 2325);
DOT 1 (4125 3700);
DOT 1 (4125 3150);
DOT 1 (4125 2825);
DOT 1 (4125 2600);
DOT 1 (4125 2150);
DOT 1 (4125 2375);
DOT 1 (4125 1925);
DOT 1 (675 2350);
DOT 1 (675 2200);
DOT 1 (-825 4400);
DOT 1 (-2975 4400);
DOT 1 (-2975 4200);
DOT 1 (-900 3200);
DOT 1 (-900 3000);
DOT 1 (-900 2800);
DOT 1 (-1225 3075);
DOT 1 (-1225 2925);
DOT 1 (-725 1675);
DOT 1 (-725 1050);
DOT 1 (-725 850);
DOT 1 (-725 650);
DOT 1 (-2975 4000);
DOT 1 (-2975 3800);
DOT 1 (-2975 3600);
DOT 1 (-2950 1875);
DOT 1 (-2950 1675);
DOT 1 (-2950 1475);
DOT 1 (-2950 1275);
DOT 1 (-2950 1025);
FORCENOTE
1:CONITINUE TO BOOT WITHOUT CLK ALIGNING
(2600 2000) 0;
DISPLAY LEFT (2600 2000);
DISPLAY 1.021277 (2600 2000);
PAINT PURPLE (2600 2000);
FORCENOTE
0: NON-LEGACY. DMI3 IS NOT INITIALIZED
(2600 1725) 0;
DISPLAY LEFT (2600 1725);
DISPLAY 1.021277 (2600 1725);
PAINT PURPLE (2600 1725);
FORCENOTE
1: CPU HAULTS UNTIL BMC RELEASES BOOT FLOW
(2725 2250) 0;
DISPLAY LEFT (2725 2250);
DISPLAY 0.893617 (2725 2250);
PAINT PURPLE (2725 2250);
FORCENOTE
0: NON-LEGACY. DMI3 IS NOT INITIALIZED
(2650 1475) 0;
DISPLAY LEFT (2650 1475);
DISPLAY 1.021277 (2650 1475);
PAINT PURPLE (2650 1475);
FORCENOTE
1: F/W IS LOCAL TO THIS SOCKET'S PCH
(2650 1550) 0;
DISPLAY LEFT (2650 1550);
DISPLAY 1.021277 (2650 1550);
PAINT PURPLE (2650 1550);
FORCENOTE
BOM_COST=PROC_SIDEBAND
(2125 650) 0;
DISPLAY LEFT (2125 650);
DISPLAY 1.957447 (2125 650);
PAINT PURPLE (2125 650);
FORCENOTE
KSFC=KEY SELECT FROM CHIPSET: SKX IGNORE
(2600 1350) 0;
DISPLAY LEFT (2600 1350);
DISPLAY 1.021277 (2600 1350);
PAINT PURPLE (2600 1350);
FORCENOTE
1: F/W IS LOCAL TO THIS SOCKET'S PCH
(2600 1800) 0;
DISPLAY LEFT (2600 1800);
DISPLAY 1.021277 (2600 1800);
PAINT PURPLE (2600 1800);
FORCENOTE
SAFE MODE BOOT (DISABLES CLOCK GATING)
(2675 3625) 0;
DISPLAY LEFT (2675 3625);
DISPLAY 0.893617 (2675 3625);
PAINT PURPLE (2675 3625);
FORCENOTE
TXT AGENT (DRIVES TXT TRANSACTIONS)
(2675 3400) 0;
DISPLAY LEFT (2675 3400);
DISPLAY 0.893617 (2675 3400);
PAINT PURPLE (2675 3400);
FORCENOTE
NOTE: PIN SHOULD ONLY BE ASSERTED ON
(2675 3250) 0;
DISPLAY LEFT (2675 3250);
DISPLAY 0.893617 (2675 3250);
PAINT PURPLE (2675 3250);
FORCENOTE
NOTE: MUST BE SET FOR ALL PROCESSORS
(2650 2925) 0;
DISPLAY LEFT (2650 2925);
DISPLAY 0.893617 (2650 2925);
PAINT PURPLE (2650 2925);
FORCENOTE
DESCRIPTION
(3225 4050) 0;
DISPLAY LEFT (3225 4050);
DISPLAY 0.893617 (3225 4050);
PAINT PURPLE (3225 4050);
FORCENOTE
      LEGACY CPU
(2675 3200) 0;
DISPLAY LEFT (2675 3200);
DISPLAY 0.893617 (2675 3200);
PAINT PURPLE (2675 3200);
FORCENOTE
TXT ENABLE
(2675 3075) 0;
DISPLAY LEFT (2675 3075);
DISPLAY 0.893617 (2675 3075);
PAINT PURPLE (2675 3075);
FORCENOTE
1: TXT ENABLED
(2725 3025) 0;
DISPLAY LEFT (2725 3025);
DISPLAY 0.893617 (2725 3025);
PAINT PURPLE (2725 3025);
FORCENOTE
0: TXT DISABLED
(2725 2975) 0;
DISPLAY LEFT (2725 2975);
DISPLAY 0.893617 (2725 2975);
PAINT PURPLE (2725 2975);
FORCENOTE
0: PCIE MODE
(2725 2650) 0;
DISPLAY LEFT (2725 2650);
DISPLAY 0.893617 (2725 2650);
PAINT PURPLE (2725 2650);
FORCENOTE
0: SAFE MODE BOOT DISABLED
(2725 3525) 0;
DISPLAY LEFT (2725 3525);
DISPLAY 0.893617 (2725 3525);
PAINT PURPLE (2725 3525);
FORCENOTE
1: SAFE MODE BOOT ENABLED
(2725 3575) 0;
DISPLAY LEFT (2725 3575);
DISPLAY 0.893617 (2725 3575);
PAINT PURPLE (2725 3575);
FORCENOTE
0: BIST DISABLED
(2725 3750) 0;
DISPLAY LEFT (2725 3750);
DISPLAY 0.893617 (2725 3750);
PAINT PURPLE (2725 3750);
FORCENOTE
1: CPU IS TXT AGENT
(2725 3350) 0;
DISPLAY LEFT (2725 3350);
DISPLAY 0.893617 (2725 3350);
PAINT PURPLE (2725 3350);
FORCENOTE
0: CPU IS NOT A TXT AGENT
(2725 3300) 0;
DISPLAY LEFT (2725 3300);
DISPLAY 0.893617 (2725 3300);
PAINT PURPLE (2725 3300);
FORCENOTE
LEGACY CPU = 00
(2725 2475) 0;
DISPLAY LEFT (2725 2475);
DISPLAY 0.893617 (2725 2475);
PAINT PURPLE (2725 2475);
FORCENOTE
SERVICE PROCESSOR BOOT MODE
(2675 2300) 0;
DISPLAY LEFT (2675 2300);
DISPLAY 0.893617 (2675 2300);
PAINT PURPLE (2675 2300);
FORCENOTE
SOCKET IDENTIFIER
(2675 2525) 0;
DISPLAY LEFT (2675 2525);
DISPLAY 0.893617 (2675 2525);
PAINT PURPLE (2675 2525);
FORCENOTE
0: NORMAL BOOT FLOW
(2725 2200) 0;
DISPLAY LEFT (2725 2200);
DISPLAY 0.893617 (2725 2200);
PAINT PURPLE (2725 2200);
FORCENOTE
      IN THE SYSTEM
(2650 2875) 0;
DISPLAY LEFT (2650 2875);
DISPLAY 0.893617 (2650 2875);
PAINT PURPLE (2650 2875);
FORCENOTE
1: BIST ENABLED
(2725 3800) 0;
DISPLAY LEFT (2725 3800);
DISPLAY 0.893617 (2725 3800);
PAINT PURPLE (2725 3800);
FORCENOTE
EXTERNAL ALIGNMENT OF RESET
(2600 2075) 0;
DISPLAY LEFT (2600 2075);
DISPLAY 1.021277 (2600 2075);
PAINT PURPLE (2600 2075);
FORCENOTE
1: DMI MODE
(2725 2700) 0;
DISPLAY LEFT (2725 2700);
DISPLAY 0.893617 (2725 2700);
PAINT PURPLE (2725 2700);
FORCENOTE
NON-LEGACY CPUS = 01 OR 10 OR 11
(2725 2425) 0;
DISPLAY LEFT (2725 2425);
DISPLAY 0.893617 (2725 2425);
PAINT PURPLE (2725 2425);
FORCENOTE
BUILT IN SELF TEST
(2675 3850) 0;
DISPLAY LEFT (2675 3850);
DISPLAY 0.914894 (2675 3850);
PAINT PURPLE (2675 3850);
FORCENOTE
CPU DMI PORT MODE
(2675 2750) 0;
DISPLAY LEFT (2675 2750);
DISPLAY 0.893617 (2675 2750);
PAINT PURPLE (2675 2750);
FORCENOTE
0
(2400 3575) 0;
DISPLAY LEFT (2400 3575);
DISPLAY 0.893617 (2400 3575);
PAINT PURPLE (2400 3575);
FORCENOTE
0
(2125 3350) 0;
DISPLAY LEFT (2125 3350);
DISPLAY 1.106383 (2125 3350);
PAINT PURPLE (2125 3350);
FORCENOTE
0
(2400 3350) 0;
DISPLAY LEFT (2400 3350);
DISPLAY 1.106383 (2400 3350);
PAINT PURPLE (2400 3350);
FORCENOTE
0
(2125 3575) 0;
DISPLAY LEFT (2125 3575);
DISPLAY 0.893617 (2125 3575);
PAINT PURPLE (2125 3575);
FORCENOTE
1
(2125 3800) 0;
DISPLAY LEFT (2125 3800);
DISPLAY 0.893617 (2125 3800);
PAINT PURPLE (2125 3800);
FORCENOTE
1
(2400 3800) 0;
DISPLAY LEFT (2400 3800);
DISPLAY 0.893617 (2400 3800);
PAINT PURPLE (2400 3800);
FORCENOTE
(DEFAULT)
(2350 3975) 0;
DISPLAY LEFT (2350 3975);
DISPLAY 0.723404 (2350 3975);
PAINT PURPLE (2350 3975);
FORCENOTE
CPU1
(2400 4050) 0;
DISPLAY LEFT (2400 4050);
DISPLAY 0.723404 (2400 4050);
PAINT PURPLE (2400 4050);
FORCENOTE
(DEFAULT)
(2050 3975) 0;
DISPLAY LEFT (2050 3975);
DISPLAY 0.723404 (2050 3975);
PAINT PURPLE (2050 3975);
FORCENOTE
CPU0
(2100 4050) 0;
DISPLAY LEFT (2100 4050);
DISPLAY 0.723404 (2100 4050);
PAINT PURPLE (2100 4050);
FORCENOTE
01
(2425 2475) 0;
DISPLAY LEFT (2425 2475);
DISPLAY 0.893617 (2425 2475);
PAINT PURPLE (2425 2475);
FORCENOTE
1
(2125 2700) 0;
DISPLAY LEFT (2125 2700);
DISPLAY 0.893617 (2125 2700);
PAINT PURPLE (2125 2700);
FORCENOTE
0
(2450 2250) 0;
DISPLAY LEFT (2450 2250);
DISPLAY 0.893617 (2450 2250);
PAINT PURPLE (2450 2250);
FORCENOTE
0
(2400 2700) 0;
DISPLAY LEFT (2400 2700);
DISPLAY 0.914894 (2400 2700);
PAINT PURPLE (2400 2700);
FORCENOTE
0
(2425 3025) 0;
DISPLAY LEFT (2425 3025);
DISPLAY 1.106383 (2425 3025);
PAINT PURPLE (2425 3025);
FORCENOTE
0
(2150 3025) 0;
DISPLAY LEFT (2150 3025);
DISPLAY 1.106383 (2150 3025);
PAINT PURPLE (2150 3025);
FORCENOTE
0
(2150 2250) 0;
DISPLAY LEFT (2150 2250);
DISPLAY 0.893617 (2150 2250);
PAINT PURPLE (2150 2250);
FORCENOTE
00
(2150 2475) 0;
DISPLAY LEFT (2150 2475);
DISPLAY 0.893617 (2150 2475);
PAINT PURPLE (2150 2475);
FORCENOTE
1
(2400 2025) 0;
DISPLAY LEFT (2400 2025);
DISPLAY 0.914894 (2400 2025);
PAINT PURPLE (2400 2025);
FORCENOTE
1
(2125 2025) 0;
DISPLAY LEFT (2125 2025);
DISPLAY 0.893617 (2125 2025);
PAINT PURPLE (2125 2025);
FORCENOTE
ROOM=PROC_SIDEBAND
(2100 775) 0;
DISPLAY LEFT (2100 775);
DISPLAY 1.957447 (2100 775);
PAINT PURPLE (2100 775);
FORCENOTE
BOOT MODE OPERATION
(2600 1875) 0;
DISPLAY LEFT (2600 1875);
DISPLAY 1.021277 (2600 1875);
PAINT PURPLE (2600 1875);
FORCENOTE
1: CNX FETCHES HASH FROM CPU
(2600 1300) 0;
DISPLAY LEFT (2600 1300);
DISPLAY 1.021277 (2600 1300);
PAINT PURPLE (2600 1300);
FORCENOTE
0: CNX FETCHES HASH FROM LBG
(2625 1250) 0;
DISPLAY LEFT (2625 1250);
DISPLAY 1.021277 (2625 1250);
PAINT PURPLE (2625 1250);
FORCENOTE
0:STALL INTERNAL_RESET FLOW
(2625 1950) 0;
DISPLAY LEFT (2625 1950);
DISPLAY 1.021277 (2625 1950);
PAINT PURPLE (2625 1950);
FORCENOTE
1
(2175 1800) 0;
DISPLAY LEFT (2175 1800);
DISPLAY 1.106383 (2175 1800);
PAINT PURPLE (2175 1800);
FORCENOTE
1
(2150 1275) 0;
DISPLAY LEFT (2150 1275);
DISPLAY 1.106383 (2150 1275);
PAINT PURPLE (2150 1275);
FORCENOTE
DMI MODE
(2650 1625) 0;
DISPLAY LEFT (2650 1625);
DISPLAY 1.021277 (2650 1625);
PAINT PURPLE (2650 1625);
FORCENOTE
1
(2450 1275) 0;
DISPLAY LEFT (2450 1275);
DISPLAY 1.106383 (2450 1275);
PAINT PURPLE (2450 1275);
FORCENOTE
1
(2150 1550) 0;
DISPLAY LEFT (2150 1550);
DISPLAY 1.106383 (2150 1550);
PAINT PURPLE (2150 1550);
FORCENOTE
0
(2450 1800) 0;
DISPLAY LEFT (2450 1800);
DISPLAY 1.106383 (2450 1800);
PAINT PURPLE (2450 1800);
FORCENOTE
0
(2450 1550) 0;
DISPLAY LEFT (2450 1550);
DISPLAY 1.106383 (2450 1550);
PAINT PURPLE (2450 1550);
FORCENOTE
MCI_BIST_ENABLE
(1025 3800) 0;
DISPLAY LEFT (1025 3800);
DISPLAY 0.893617 (1025 3800);
PAINT PURPLE (1025 3800);
FORCENOTE
MCI_SAFE_MODE_BOOT
(1025 3575) 0;
DISPLAY LEFT (1025 3575);
DISPLAY 0.893617 (1025 3575);
PAINT PURPLE (1025 3575);
FORCENOTE
MCI_TXT_AGENT
(1025 3350) 0;
DISPLAY LEFT (1025 3350);
DISPLAY 0.893617 (1025 3350);
PAINT PURPLE (1025 3350);
FORCENOTE
PD
(1825 3350) 0;
DISPLAY LEFT (1825 3350);
DISPLAY 0.893617 (1825 3350);
PAINT PURPLE (1825 3350);
FORCENOTE
PD
(1825 3575) 0;
DISPLAY LEFT (1825 3575);
DISPLAY 0.893617 (1825 3575);
PAINT PURPLE (1825 3575);
FORCENOTE
INTERNAL
(1775 4050) 0;
DISPLAY LEFT (1775 4050);
DISPLAY 0.723404 (1775 4050);
PAINT PURPLE (1775 4050);
FORCENOTE
PU
(1825 3800) 0;
DISPLAY LEFT (1825 3800);
DISPLAY 0.893617 (1825 3800);
PAINT PURPLE (1825 3800);
FORCENOTE
SKX PIN NAME
(1125 4050) 0;
DISPLAY LEFT (1125 4050);
DISPLAY 0.893617 (1125 4050);
PAINT PURPLE (1125 4050);
FORCENOTE
PU/PD
(1800 3975) 0;
DISPLAY LEFT (1800 3975);
DISPLAY 0.723404 (1800 3975);
PAINT PURPLE (1800 3975);
FORCENOTE
BMCINIT
(1025 2250) 0;
DISPLAY LEFT (1025 2250);
DISPLAY 0.893617 (1025 2250);
PAINT PURPLE (1025 2250);
FORCENOTE
MCI_FRMAGENT
(1025 2700) 0;
DISPLAY LEFT (1025 2700);
DISPLAY 0.893617 (1025 2700);
PAINT PURPLE (1025 2700);
FORCENOTE
PD
(1825 2250) 0;
DISPLAY LEFT (1825 2250);
DISPLAY 0.893617 (1825 2250);
PAINT PURPLE (1825 2250);
FORCENOTE
MCI_SOCKET_ID[1..0]
(1025 2475) 0;
DISPLAY LEFT (1025 2475);
DISPLAY 0.893617 (1025 2475);
PAINT PURPLE (1025 2475);
FORCENOTE
PD
(1825 2700) 0;
DISPLAY LEFT (1825 2700);
DISPLAY 0.723404 (1825 2700);
PAINT PURPLE (1825 2700);
FORCENOTE
PU
(1825 3025) 0;
DISPLAY LEFT (1825 3025);
DISPLAY 0.893617 (1825 3025);
PAINT PURPLE (1825 3025);
FORCENOTE
PD
(1825 2475) 0;
DISPLAY LEFT (1825 2475);
DISPLAY 0.893617 (1825 2475);
PAINT PURPLE (1825 2475);
FORCENOTE
MCI_TXT_PLTEN
(1025 3025) 0;
DISPLAY LEFT (1025 3025);
DISPLAY 0.893617 (1025 3025);
PAINT PURPLE (1025 3025);
FORCENOTE
PU
(1825 2025) 0;
DISPLAY LEFT (1825 2025);
DISPLAY 0.893617 (1825 2025);
PAINT PURPLE (1825 2025);
FORCENOTE
EAR_N
(1025 2025) 0;
DISPLAY LEFT (1025 2025);
DISPLAY 0.893617 (1025 2025);
PAINT PURPLE (1025 2025);
FORCENOTE
PD
(1825 1800) 0;
DISPLAY LEFT (1825 1800);
DISPLAY 0.893617 (1825 1800);
PAINT PURPLE (1825 1800);
FORCENOTE
PU
(1825 1275) 0;
DISPLAY LEFT (1825 1275);
DISPLAY 0.893617 (1825 1275);
PAINT PURPLE (1825 1275);
FORCENOTE
PU
(1825 1550) 0;
DISPLAY LEFT (1825 1550);
DISPLAY 0.893617 (1825 1550);
PAINT PURPLE (1825 1550);
FORCENOTE
KSFC_DIS
(1075 1250) 0;
DISPLAY LEFT (1075 1250);
DISPLAY 1.021277 (1075 1250);
PAINT PURPLE (1075 1250);
FORCENOTE
LEGACY_SXT
(1025 1800) 0;
DISPLAY LEFT (1025 1800);
DISPLAY 0.893617 (1025 1800);
PAINT PURPLE (1025 1800);
FORCENOTE
DMIMODE_OVERRIDE
(1050 1550) 0;
DISPLAY LEFT (1050 1550);
DISPLAY 0.893617 (1050 1550);
PAINT PURPLE (1050 1550);
FORCENOTE
STRAPS (CPU0) 
(-3400 4875) 0;
DISPLAY LEFT (-3400 4875);
DISPLAY 1.595745 (-3400 4875);
PAINT PURPLE (-3400 4875);
FORCENOTE
STRAPS (CPU1) 
(-3425 2400) 0;
DISPLAY LEFT (-3425 2400);
DISPLAY 1.595745 (-3425 2400);
PAINT PURPLE (-3425 2400);
QUIT
